FILE_TYPE = MACRO_DRAWING;
SET COLOR_WIRE YELLOW;
SET COLOR_PROP MONO;
SET COLOR_DOT WHITE;
SET COLOR_ARC YELLOW;
SET COLOR_BODY GREEN;
SET COLOR_NOTE MONO;
SET PROP_DISPLAY VALUE;
SET PAGE_NUMBER P80;
FORCEADD GND..1
R 2
(-7825 1350);
FORCEPROP 3 LASTPIN (-7825 1400) SIG_NAME GND\g
J 0
(-7815 1410);
DISPLAY 0.659574 (-7815 1410);
PAINT MONO (-7815 1410);
DISPLAY INVISIBLE (-7815 1410);
FORCEPROP 1 LAST VOLTAGE 0
J 0
(-7825 1350);
PAINT SKYBLUE (-7825 1350);
DISPLAY INVISIBLE (-7825 1350);
FORCEPROP 2 LAST CDS_LIB mstr_symbols
J 0
(-7825 1350);
DISPLAY 0.787234 (-7825 1350);
PAINT MONO (-7825 1350);
DISPLAY INVISIBLE (-7825 1350);
FORCEPROP 1 LAST SIZE 1B
J 2
(-7900 1300);
DISPLAY 1.170213 (-7900 1300);
PAINT GREEN (-7900 1300);
DISPLAY INVISIBLE (-7900 1300);
FORCEPROP 2 LAST BOM_COST MEM
J 0
(-7825 1355);
PAINT ORANGE (-7825 1355);
DISPLAY INVISIBLE (-7825 1355);
FORCEPROP 1 LAST BODY_TYPE PLUMBING
J 2
(-7780 1307);
DISPLAY 0.340426 (-7780 1307);
PAINT GREEN (-7780 1307);
DISPLAY INVISIBLE (-7780 1307);
FORCEPROP 1 LAST PATH I1
J 2
(-7900 1350);
DISPLAY 0.872340 (-7900 1350);
PAINT AQUA (-7900 1350);
DISPLAY INVISIBLE (-7900 1350);
FORCEPROP 2 LAST ROOM DDR4_GH_G
J 0
(-7825 1355);
PAINT ORANGE (-7825 1355);
DISPLAY INVISIBLE (-7825 1355);
FORCEPROP 1 LAST HDL_POWER GND
J 2
(-7825 1500);
DISPLAY 0.553191 (-7825 1500);
PAINT GREEN (-7825 1500);
DISPLAY INVISIBLE (-7825 1500);
FORCEADD OFFPAGE..1
(-6625 1650);
FORCEPROP 2 LAST $XR1 79 
J 0
(-6966 1650);
DISPLAY 0.638298 (-6966 1650);
PAINT MONO (-6966 1650);
FORCEPROP 2 LAST $XR0 58 
J 0
(-6876 1650);
DISPLAY 0.638298 (-6876 1650);
PAINT MONO (-6876 1650);
FORCEPROP 2 LAST CDS_LIB mstr_standard
J 0
(-6625 1650);
DISPLAY 0.787234 (-6625 1650);
PAINT MONO (-6625 1650);
DISPLAY INVISIBLE (-6625 1650);
FORCEPROP 1 LAST OFFPAGE TRUE
J 0
(-6300 1525);
DISPLAY 0.936170 (-6300 1525);
PAINT GREEN (-6300 1525);
DISPLAY INVISIBLE (-6300 1525);
FORCEPROP 1 LAST COMMENT_BODY TRUE
J 0
(-6500 1550);
DISPLAY 0.936170 (-6500 1550);
PAINT GREEN (-6500 1550);
DISPLAY INVISIBLE (-6500 1550);
FORCEPROP 2 LAST PATH I10
J 0
(-6875 1700);
DISPLAY 1.021277 (-6875 1700);
PAINT ORANGE (-6875 1700);
DISPLAY INVISIBLE (-6875 1700);
FORCEADD TAP..6
R 2
(-4475 3450);
FORCEPROP 3 LASTPIN (-4525 3450) SIG_NAME M_H_DQ<45>
J 0
(-4515 3460);
DISPLAY 0.659574 (-4515 3460);
PAINT MONO (-4515 3460);
DISPLAY INVISIBLE (-4515 3460);
FORCEPROP 1 LASTPIN (-4525 3450) BN 45
J 2
(-4475 3460);
DISPLAY 0.617021 (-4475 3460);
PAINT PINK (-4475 3460);
FORCEPROP 2 LAST CDS_LIB mstr_standard
J 2
(-4475 3450);
DISPLAY 0.787234 (-4475 3450);
PAINT MONO (-4475 3450);
DISPLAY INVISIBLE (-4475 3450);
FORCEPROP 1 LAST BODY_TYPE PLUMBING
J 2
(-4475 3400);
DISPLAY 1.234043 (-4475 3400);
PAINT GREEN (-4475 3400);
DISPLAY INVISIBLE (-4475 3400);
FORCEPROP 1 LAST HDL_TAP TRUE
J 2
(-4800 3325);
DISPLAY 1.234043 (-4800 3325);
PAINT GREEN (-4800 3325);
DISPLAY INVISIBLE (-4800 3325);
FORCEPROP 1 LAST PATH I100
J 2
(-4473 3450);
DISPLAY 0.872340 (-4473 3450);
PAINT GREEN (-4473 3450);
DISPLAY INVISIBLE (-4473 3450);
FORCEADD SCONN288_H44441003..2
(-2675 3750);
FORCEPROP 1 LAST LOCATION J9U1
J 0
(-3075 4850);
DISPLAY 0.617021 (-3075 4850);
PAINT AQUA (-3075 4850);
FORCEPROP 1 LAST PART_NUMBER H44441-003
J 0
(-3075 2650);
DISPLAY 0.617021 (-3075 2650);
PAINT BLUE (-3075 2650);
FORCEPROP 1 LAST MATERIAL SCONN
J 0
(-3075 4800);
DISPLAY 0.617021 (-3075 4800);
PAINT SKYBLUE (-3075 4800);
FORCEPROP 2 LASTPIN (-2225 4600) $PN 51
J 0
(-2215 4610);
DISPLAY 0.617021 (-2215 4610);
PAINT ORANGE (-2215 4610);
FORCEPROP 2 LASTPIN (-2225 4550) $PN 52
J 0
(-2215 4560);
DISPLAY 0.617021 (-2215 4560);
PAINT ORANGE (-2215 4560);
FORCEPROP 2 LASTPIN (-2225 4500) $PN 132
J 0
(-2215 4510);
DISPLAY 0.617021 (-2215 4510);
PAINT ORANGE (-2215 4510);
FORCEPROP 2 LASTPIN (-2225 4450) $PN 133
J 0
(-2215 4460);
DISPLAY 0.617021 (-2215 4460);
PAINT ORANGE (-2215 4460);
FORCEPROP 2 LASTPIN (-2225 4400) $PN 121
J 0
(-2215 4410);
DISPLAY 0.617021 (-2215 4410);
PAINT ORANGE (-2215 4410);
FORCEPROP 2 LASTPIN (-2225 4350) $PN 122
J 0
(-2215 4360);
DISPLAY 0.617021 (-2215 4360);
PAINT ORANGE (-2215 4360);
FORCEPROP 2 LASTPIN (-2225 4300) $PN 110
J 0
(-2215 4310);
DISPLAY 0.617021 (-2215 4310);
PAINT ORANGE (-2215 4310);
FORCEPROP 2 LASTPIN (-2225 4250) $PN 111
J 0
(-2215 4260);
DISPLAY 0.617021 (-2215 4260);
PAINT ORANGE (-2215 4260);
FORCEPROP 2 LASTPIN (-2225 4200) $PN 99
J 0
(-2215 4210);
DISPLAY 0.617021 (-2215 4210);
PAINT ORANGE (-2215 4210);
FORCEPROP 2 LASTPIN (-2225 4150) $PN 100
J 0
(-2215 4160);
DISPLAY 0.617021 (-2215 4160);
PAINT ORANGE (-2215 4160);
FORCEPROP 2 LASTPIN (-2225 4100) $PN 40
J 0
(-2215 4110);
DISPLAY 0.617021 (-2215 4110);
PAINT ORANGE (-2215 4110);
FORCEPROP 2 LASTPIN (-2225 4050) $PN 41
J 0
(-2215 4060);
DISPLAY 0.617021 (-2215 4060);
PAINT ORANGE (-2215 4060);
FORCEPROP 2 LASTPIN (-2225 4000) $PN 29
J 0
(-2215 4010);
DISPLAY 0.617021 (-2215 4010);
PAINT ORANGE (-2215 4010);
FORCEPROP 2 LASTPIN (-2225 3950) $PN 30
J 0
(-2215 3960);
DISPLAY 0.617021 (-2215 3960);
PAINT ORANGE (-2215 3960);
FORCEPROP 2 LASTPIN (-2225 3850) $PN 19
J 0
(-2215 3860);
DISPLAY 0.617021 (-2215 3860);
PAINT ORANGE (-2215 3860);
FORCEPROP 2 LASTPIN (-2225 3800) $PN 7
J 0
(-2215 3810);
DISPLAY 0.617021 (-2215 3810);
PAINT ORANGE (-2215 3810);
FORCEPROP 2 LASTPIN (-2225 3750) $PN 8
J 0
(-2215 3760);
DISPLAY 0.617021 (-2215 3760);
PAINT ORANGE (-2215 3760);
FORCEPROP 2 LASTPIN (-2225 3700) $PN 197
J 0
(-2215 3710);
DISPLAY 0.617021 (-2215 3710);
PAINT ORANGE (-2215 3710);
FORCEPROP 2 LASTPIN (-2225 3650) $PN 196
J 0
(-2215 3660);
DISPLAY 0.617021 (-2215 3660);
PAINT ORANGE (-2215 3660);
FORCEPROP 2 LASTPIN (-2225 3600) $PN 278
J 0
(-2215 3610);
DISPLAY 0.617021 (-2215 3610);
PAINT ORANGE (-2215 3610);
FORCEPROP 2 LASTPIN (-2225 3500) $PN 267
J 0
(-2215 3510);
DISPLAY 0.617021 (-2215 3510);
PAINT ORANGE (-2215 3510);
FORCEPROP 2 LASTPIN (-2225 3450) $PN 266
J 0
(-2215 3460);
DISPLAY 0.617021 (-2215 3460);
PAINT ORANGE (-2215 3460);
FORCEPROP 2 LASTPIN (-2225 3400) $PN 256
J 0
(-2215 3410);
DISPLAY 0.617021 (-2215 3410);
PAINT ORANGE (-2215 3410);
FORCEPROP 2 LASTPIN (-2225 3350) $PN 255
J 0
(-2215 3360);
DISPLAY 0.617021 (-2215 3360);
PAINT ORANGE (-2215 3360);
FORCEPROP 2 LASTPIN (-2225 3300) $PN 245
J 0
(-2215 3310);
DISPLAY 0.617021 (-2215 3310);
PAINT ORANGE (-2215 3310);
FORCEPROP 2 LASTPIN (-2225 3200) $PN 186
J 0
(-2215 3210);
DISPLAY 0.617021 (-2215 3210);
PAINT ORANGE (-2215 3210);
FORCEPROP 2 LASTPIN (-2225 3100) $PN 175
J 0
(-2215 3110);
DISPLAY 0.617021 (-2215 3110);
PAINT ORANGE (-2215 3110);
FORCEPROP 2 LASTPIN (-2225 3050) $PN 174
J 0
(-2215 3060);
DISPLAY 0.617021 (-2215 3060);
PAINT ORANGE (-2215 3060);
FORCEPROP 2 LASTPIN (-2225 3000) $PN 164
J 0
(-2215 3010);
DISPLAY 0.617021 (-2215 3010);
PAINT ORANGE (-2215 3010);
FORCEPROP 2 LASTPIN (-2225 2900) $PN 153
J 0
(-2215 2910);
DISPLAY 0.617021 (-2215 2910);
PAINT ORANGE (-2215 2910);
FORCEPROP 2 LASTPIN (-2225 2850) $PN 152
J 0
(-2215 2860);
DISPLAY 0.617021 (-2215 2860);
PAINT ORANGE (-2215 2860);
FORCEPROP 2 LASTPIN (-2225 3250) $PN 244
J 0
(-2215 3260);
DISPLAY 0.617021 (-2215 3260);
PAINT ORANGE (-2215 3260);
FORCEPROP 2 LASTPIN (-2225 2950) $PN 163
J 0
(-2215 2960);
DISPLAY 0.617021 (-2215 2960);
PAINT ORANGE (-2215 2960);
FORCEPROP 2 LASTPIN (-2225 3900) $PN 18
J 0
(-2215 3910);
DISPLAY 0.617021 (-2215 3910);
PAINT ORANGE (-2215 3910);
FORCEPROP 2 LASTPIN (-2225 3150) $PN 185
J 0
(-2215 3160);
DISPLAY 0.617021 (-2215 3160);
PAINT ORANGE (-2215 3160);
FORCEPROP 0 LAST BOM_SS NOPOP
J 0
(-2878 4836);
DISPLAY 1.021277 (-2878 4836);
PAINT BROWN (-2878 4836);
DISPLAY BOTH (-2878 4836);
FORCEPROP 2 LASTPIN (-2225 3550) $PN 277
J 0
(-2215 3560);
DISPLAY 0.617021 (-2215 3560);
PAINT ORANGE (-2215 3560);
FORCEPROP 1 LAST PACK_TYPE PIP
J 0
(-3075 4900);
PAINT SKYBLUE (-3075 4900);
DISPLAY INVISIBLE (-3075 4900);
FORCEPROP 2 LAST BOM_COST MEM
J 0
(-2675 3750);
PAINT ORANGE (-2675 3750);
DISPLAY INVISIBLE (-2675 3750);
FORCEPROP 2 LAST CDS_LIB mstr_sconn
J 0
(-2675 3750);
PAINT ORANGE (-2675 3750);
DISPLAY INVISIBLE (-2675 3750);
FORCEPROP 2 LAST SEC_TYPE PIP
J 0
(-3075 4900);
DISPLAY 1.021277 (-3075 4900);
PAINT ORANGE (-3075 4900);
DISPLAY INVISIBLE (-3075 4900);
FORCEPROP 2 LAST SEC 2
J 0
(-3075 4900);
DISPLAY 0.680851 (-3075 4900);
PAINT MONO (-3075 4900);
DISPLAY INVISIBLE (-3075 4900);
FORCEPROP 2 LAST CDS_LOCATION J9U1
J 0
(-3075 4850);
DISPLAY 0.617021 (-3075 4850);
PAINT AQUA (-3075 4850);
DISPLAY INVISIBLE (-3075 4850);
FORCEPROP 1 LAST PATH I101
J 0
(-2675 4800);
PAINT GREEN (-2675 4800);
DISPLAY INVISIBLE (-2675 4800);
FORCEPROP 2 LAST ROOM DDR4_GH_H
J 0
(-2675 3750);
PAINT ORANGE (-2675 3750);
DISPLAY INVISIBLE (-2675 3750);
FORCEADD TAP..6
(-5975 3550);
FORCEPROP 3 LASTPIN (-5925 3550) SIG_NAME M_H_MA<1>
J 0
(-5915 3560);
DISPLAY 0.659574 (-5915 3560);
PAINT MONO (-5915 3560);
DISPLAY INVISIBLE (-5915 3560);
FORCEPROP 1 LASTPIN (-5925 3550) BN 1
J 0
(-5975 3560);
DISPLAY 0.617021 (-5975 3560);
PAINT PINK (-5975 3560);
FORCEPROP 2 LAST CDS_LIB mstr_standard
J 2
(-5975 3550);
DISPLAY 0.787234 (-5975 3550);
PAINT MONO (-5975 3550);
DISPLAY INVISIBLE (-5975 3550);
FORCEPROP 1 LAST BODY_TYPE PLUMBING
J 0
(-5975 3500);
DISPLAY 1.234043 (-5975 3500);
PAINT GREEN (-5975 3500);
DISPLAY INVISIBLE (-5975 3500);
FORCEPROP 1 LAST HDL_TAP TRUE
J 0
(-5650 3425);
DISPLAY 1.234043 (-5650 3425);
PAINT GREEN (-5650 3425);
DISPLAY INVISIBLE (-5650 3425);
FORCEPROP 1 LAST PATH I102
J 0
(-5977 3550);
DISPLAY 0.872340 (-5977 3550);
PAINT GREEN (-5977 3550);
DISPLAY INVISIBLE (-5977 3550);
FORCEADD TAP..6
(-5975 3600);
FORCEPROP 3 LASTPIN (-5925 3600) SIG_NAME M_H_MA<2>
J 0
(-5915 3610);
DISPLAY 0.659574 (-5915 3610);
PAINT MONO (-5915 3610);
DISPLAY INVISIBLE (-5915 3610);
FORCEPROP 1 LASTPIN (-5925 3600) BN 2
J 0
(-5975 3610);
DISPLAY 0.617021 (-5975 3610);
PAINT PINK (-5975 3610);
FORCEPROP 2 LAST CDS_LIB mstr_standard
J 2
(-5975 3600);
DISPLAY 0.787234 (-5975 3600);
PAINT MONO (-5975 3600);
DISPLAY INVISIBLE (-5975 3600);
FORCEPROP 1 LAST BODY_TYPE PLUMBING
J 0
(-5975 3550);
DISPLAY 1.234043 (-5975 3550);
PAINT GREEN (-5975 3550);
DISPLAY INVISIBLE (-5975 3550);
FORCEPROP 1 LAST HDL_TAP TRUE
J 0
(-5650 3475);
DISPLAY 1.234043 (-5650 3475);
PAINT GREEN (-5650 3475);
DISPLAY INVISIBLE (-5650 3475);
FORCEPROP 1 LAST PATH I103
J 0
(-5977 3600);
DISPLAY 0.872340 (-5977 3600);
PAINT GREEN (-5977 3600);
DISPLAY INVISIBLE (-5977 3600);
FORCEADD TAP..6
(-5975 3650);
FORCEPROP 3 LASTPIN (-5925 3650) SIG_NAME M_H_MA<3>
J 0
(-5915 3660);
DISPLAY 0.659574 (-5915 3660);
PAINT MONO (-5915 3660);
DISPLAY INVISIBLE (-5915 3660);
FORCEPROP 1 LASTPIN (-5925 3650) BN 3
J 0
(-5975 3660);
DISPLAY 0.617021 (-5975 3660);
PAINT PINK (-5975 3660);
FORCEPROP 2 LAST CDS_LIB mstr_standard
J 2
(-5975 3650);
DISPLAY 0.787234 (-5975 3650);
PAINT MONO (-5975 3650);
DISPLAY INVISIBLE (-5975 3650);
FORCEPROP 1 LAST BODY_TYPE PLUMBING
J 0
(-5975 3600);
DISPLAY 1.234043 (-5975 3600);
PAINT GREEN (-5975 3600);
DISPLAY INVISIBLE (-5975 3600);
FORCEPROP 1 LAST HDL_TAP TRUE
J 0
(-5650 3525);
DISPLAY 1.234043 (-5650 3525);
PAINT GREEN (-5650 3525);
DISPLAY INVISIBLE (-5650 3525);
FORCEPROP 1 LAST PATH I104
J 0
(-5977 3650);
DISPLAY 0.872340 (-5977 3650);
PAINT GREEN (-5977 3650);
DISPLAY INVISIBLE (-5977 3650);
FORCEADD TAP..6
(-5975 3750);
FORCEPROP 3 LASTPIN (-5925 3750) SIG_NAME M_H_MA<5>
J 0
(-5915 3760);
DISPLAY 0.659574 (-5915 3760);
PAINT MONO (-5915 3760);
DISPLAY INVISIBLE (-5915 3760);
FORCEPROP 1 LASTPIN (-5925 3750) BN 5
J 0
(-5975 3760);
DISPLAY 0.617021 (-5975 3760);
PAINT PINK (-5975 3760);
FORCEPROP 2 LAST CDS_LIB mstr_standard
J 2
(-5975 3750);
DISPLAY 0.787234 (-5975 3750);
PAINT MONO (-5975 3750);
DISPLAY INVISIBLE (-5975 3750);
FORCEPROP 1 LAST BODY_TYPE PLUMBING
J 0
(-5975 3700);
DISPLAY 1.234043 (-5975 3700);
PAINT GREEN (-5975 3700);
DISPLAY INVISIBLE (-5975 3700);
FORCEPROP 1 LAST HDL_TAP TRUE
J 0
(-5650 3625);
DISPLAY 1.234043 (-5650 3625);
PAINT GREEN (-5650 3625);
DISPLAY INVISIBLE (-5650 3625);
FORCEPROP 1 LAST PATH I105
J 0
(-5977 3750);
DISPLAY 0.872340 (-5977 3750);
PAINT GREEN (-5977 3750);
DISPLAY INVISIBLE (-5977 3750);
FORCEADD TAP..6
(-5975 3700);
FORCEPROP 3 LASTPIN (-5925 3700) SIG_NAME M_H_MA<4>
J 0
(-5915 3710);
DISPLAY 0.659574 (-5915 3710);
PAINT MONO (-5915 3710);
DISPLAY INVISIBLE (-5915 3710);
FORCEPROP 1 LASTPIN (-5925 3700) BN 4
J 0
(-5975 3710);
DISPLAY 0.617021 (-5975 3710);
PAINT PINK (-5975 3710);
FORCEPROP 2 LAST CDS_LIB mstr_standard
J 2
(-5975 3700);
DISPLAY 0.787234 (-5975 3700);
PAINT MONO (-5975 3700);
DISPLAY INVISIBLE (-5975 3700);
FORCEPROP 1 LAST BODY_TYPE PLUMBING
J 0
(-5975 3650);
DISPLAY 1.234043 (-5975 3650);
PAINT GREEN (-5975 3650);
DISPLAY INVISIBLE (-5975 3650);
FORCEPROP 1 LAST HDL_TAP TRUE
J 0
(-5650 3575);
DISPLAY 1.234043 (-5650 3575);
PAINT GREEN (-5650 3575);
DISPLAY INVISIBLE (-5650 3575);
FORCEPROP 1 LAST PATH I106
J 0
(-5977 3700);
DISPLAY 0.872340 (-5977 3700);
PAINT GREEN (-5977 3700);
DISPLAY INVISIBLE (-5977 3700);
FORCEADD TAP..6
(-5975 3800);
FORCEPROP 3 LASTPIN (-5925 3800) SIG_NAME M_H_MA<6>
J 0
(-5915 3810);
DISPLAY 0.659574 (-5915 3810);
PAINT MONO (-5915 3810);
DISPLAY INVISIBLE (-5915 3810);
FORCEPROP 1 LASTPIN (-5925 3800) BN 6
J 0
(-5975 3810);
DISPLAY 0.617021 (-5975 3810);
PAINT PINK (-5975 3810);
FORCEPROP 2 LAST CDS_LIB mstr_standard
J 2
(-5975 3800);
DISPLAY 0.787234 (-5975 3800);
PAINT MONO (-5975 3800);
DISPLAY INVISIBLE (-5975 3800);
FORCEPROP 1 LAST BODY_TYPE PLUMBING
J 0
(-5975 3750);
DISPLAY 1.234043 (-5975 3750);
PAINT GREEN (-5975 3750);
DISPLAY INVISIBLE (-5975 3750);
FORCEPROP 1 LAST HDL_TAP TRUE
J 0
(-5650 3675);
DISPLAY 1.234043 (-5650 3675);
PAINT GREEN (-5650 3675);
DISPLAY INVISIBLE (-5650 3675);
FORCEPROP 1 LAST PATH I107
J 0
(-5977 3800);
DISPLAY 0.872340 (-5977 3800);
PAINT GREEN (-5977 3800);
DISPLAY INVISIBLE (-5977 3800);
FORCEADD TAP..6
(-5975 3900);
FORCEPROP 3 LASTPIN (-5925 3900) SIG_NAME M_H_MA<8>
J 0
(-5915 3910);
DISPLAY 0.659574 (-5915 3910);
PAINT MONO (-5915 3910);
DISPLAY INVISIBLE (-5915 3910);
FORCEPROP 1 LASTPIN (-5925 3900) BN 8
J 0
(-5975 3910);
DISPLAY 0.617021 (-5975 3910);
PAINT PINK (-5975 3910);
FORCEPROP 2 LAST CDS_LIB mstr_standard
J 2
(-5975 3900);
DISPLAY 0.787234 (-5975 3900);
PAINT MONO (-5975 3900);
DISPLAY INVISIBLE (-5975 3900);
FORCEPROP 1 LAST BODY_TYPE PLUMBING
J 0
(-5975 3850);
DISPLAY 1.234043 (-5975 3850);
PAINT GREEN (-5975 3850);
DISPLAY INVISIBLE (-5975 3850);
FORCEPROP 1 LAST HDL_TAP TRUE
J 0
(-5650 3775);
DISPLAY 1.234043 (-5650 3775);
PAINT GREEN (-5650 3775);
DISPLAY INVISIBLE (-5650 3775);
FORCEPROP 1 LAST PATH I108
J 0
(-5977 3900);
DISPLAY 0.872340 (-5977 3900);
PAINT GREEN (-5977 3900);
DISPLAY INVISIBLE (-5977 3900);
FORCEADD TAP..6
(-5975 3850);
FORCEPROP 3 LASTPIN (-5925 3850) SIG_NAME M_H_MA<7>
J 0
(-5915 3860);
DISPLAY 0.659574 (-5915 3860);
PAINT MONO (-5915 3860);
DISPLAY INVISIBLE (-5915 3860);
FORCEPROP 1 LASTPIN (-5925 3850) BN 7
J 0
(-5975 3860);
DISPLAY 0.617021 (-5975 3860);
PAINT PINK (-5975 3860);
FORCEPROP 2 LAST CDS_LIB mstr_standard
J 2
(-5975 3850);
DISPLAY 0.787234 (-5975 3850);
PAINT MONO (-5975 3850);
DISPLAY INVISIBLE (-5975 3850);
FORCEPROP 1 LAST BODY_TYPE PLUMBING
J 0
(-5975 3800);
DISPLAY 1.234043 (-5975 3800);
PAINT GREEN (-5975 3800);
DISPLAY INVISIBLE (-5975 3800);
FORCEPROP 1 LAST HDL_TAP TRUE
J 0
(-5650 3725);
DISPLAY 1.234043 (-5650 3725);
PAINT GREEN (-5650 3725);
DISPLAY INVISIBLE (-5650 3725);
FORCEPROP 1 LAST PATH I109
J 0
(-5977 3850);
DISPLAY 0.872340 (-5977 3850);
PAINT GREEN (-5977 3850);
DISPLAY INVISIBLE (-5977 3850);
FORCEADD OFFPAGE..5
(-6950 2050);
FORCEPROP 2 LAST $XR23 94 
J 0
(-7444 2086);
DISPLAY 0.638298 (-7444 2086);
PAINT MONO (-7444 2086);
FORCEPROP 2 LAST $XR22 88 
J 0
(-7354 2086);
DISPLAY 0.638298 (-7354 2086);
PAINT MONO (-7354 2086);
FORCEPROP 2 LAST $XR21 87 
J 0
(-7264 2086);
DISPLAY 0.638298 (-7264 2086);
PAINT MONO (-7264 2086);
FORCEPROP 2 LAST $XR20 86 
J 0
(-7174 2086);
DISPLAY 0.638298 (-7174 2086);
PAINT MONO (-7174 2086);
FORCEPROP 2 LAST $XR19 85 
J 0
(-7984 2014);
DISPLAY 0.638298 (-7984 2014);
PAINT MONO (-7984 2014);
FORCEPROP 2 LAST $XR18 84 
J 0
(-7894 2014);
DISPLAY 0.638298 (-7894 2014);
PAINT MONO (-7894 2014);
FORCEPROP 2 LAST $XR17 83 
J 0
(-7804 2014);
DISPLAY 0.638298 (-7804 2014);
PAINT MONO (-7804 2014);
FORCEPROP 2 LAST $XR16 82 
J 0
(-7714 2014);
DISPLAY 0.638298 (-7714 2014);
PAINT MONO (-7714 2014);
FORCEPROP 2 LAST $XR15 81 
J 0
(-7624 2014);
DISPLAY 0.638298 (-7624 2014);
PAINT MONO (-7624 2014);
FORCEPROP 2 LAST $XR14 79 
J 0
(-7534 2014);
DISPLAY 0.638298 (-7534 2014);
PAINT MONO (-7534 2014);
FORCEPROP 2 LAST $XR13 78 
J 0
(-7444 2014);
DISPLAY 0.638298 (-7444 2014);
PAINT MONO (-7444 2014);
FORCEPROP 2 LAST $XR12 77 
J 0
(-7354 2014);
DISPLAY 0.638298 (-7354 2014);
PAINT MONO (-7354 2014);
FORCEPROP 2 LAST $XR11 54 
J 0
(-7264 2014);
DISPLAY 0.638298 (-7264 2014);
PAINT MONO (-7264 2014);
FORCEPROP 2 LAST $XR10 53 
J 0
(-7174 2014);
DISPLAY 0.638298 (-7174 2014);
PAINT MONO (-7174 2014);
FORCEPROP 2 LAST $XR9 52 
J 0
(-7984 2050);
DISPLAY 0.638298 (-7984 2050);
PAINT MONO (-7984 2050);
FORCEPROP 2 LAST $XR8 51 
J 0
(-7894 2050);
DISPLAY 0.638298 (-7894 2050);
PAINT MONO (-7894 2050);
FORCEPROP 2 LAST $XR7 50 
J 0
(-7804 2050);
DISPLAY 0.638298 (-7804 2050);
PAINT MONO (-7804 2050);
FORCEPROP 2 LAST $XR6 49 
J 0
(-7714 2050);
DISPLAY 0.638298 (-7714 2050);
PAINT MONO (-7714 2050);
FORCEPROP 2 LAST $XR5 48 
J 0
(-7624 2050);
DISPLAY 0.638298 (-7624 2050);
PAINT MONO (-7624 2050);
FORCEPROP 2 LAST $XR4 47 
J 0
(-7534 2050);
DISPLAY 0.638298 (-7534 2050);
PAINT MONO (-7534 2050);
FORCEPROP 2 LAST $XR3 46 
J 0
(-7444 2050);
DISPLAY 0.638298 (-7444 2050);
PAINT MONO (-7444 2050);
FORCEPROP 2 LAST $XR2 45 
J 0
(-7354 2050);
DISPLAY 0.638298 (-7354 2050);
PAINT MONO (-7354 2050);
FORCEPROP 2 LAST $XR1 44 
J 0
(-7264 2050);
DISPLAY 0.638298 (-7264 2050);
PAINT MONO (-7264 2050);
FORCEPROP 2 LAST $XR0 43 
J 0
(-7174 2050);
DISPLAY 0.638298 (-7174 2050);
PAINT MONO (-7174 2050);
FORCEPROP 2 LAST CDS_LIB mstr_standard
J 0
(-6950 2050);
DISPLAY 0.787234 (-6950 2050);
PAINT MONO (-6950 2050);
DISPLAY INVISIBLE (-6950 2050);
FORCEPROP 1 LAST OFFPAGE TRUE
J 0
(-6625 1925);
DISPLAY 1.404255 (-6625 1925);
PAINT GREEN (-6625 1925);
DISPLAY INVISIBLE (-6625 1925);
FORCEPROP 1 LAST COMMENT_BODY TRUE
J 0
(-6850 1975);
DISPLAY 1.404255 (-6850 1975);
PAINT GREEN (-6850 1975);
DISPLAY INVISIBLE (-6850 1975);
FORCEPROP 2 LAST PATH I11
J 0
(-7200 2100);
DISPLAY 1.021277 (-7200 2100);
PAINT ORANGE (-7200 2100);
DISPLAY INVISIBLE (-7200 2100);
FORCEADD TAP..6
(-5975 4000);
FORCEPROP 3 LASTPIN (-5925 4000) SIG_NAME M_H_MA<10>
J 0
(-5915 4010);
DISPLAY 0.659574 (-5915 4010);
PAINT MONO (-5915 4010);
DISPLAY INVISIBLE (-5915 4010);
FORCEPROP 1 LASTPIN (-5925 4000) BN 10
J 0
(-5975 4010);
DISPLAY 0.617021 (-5975 4010);
PAINT PINK (-5975 4010);
FORCEPROP 2 LAST CDS_LIB mstr_standard
J 2
(-5975 4000);
DISPLAY 0.787234 (-5975 4000);
PAINT MONO (-5975 4000);
DISPLAY INVISIBLE (-5975 4000);
FORCEPROP 1 LAST BODY_TYPE PLUMBING
J 0
(-5975 3950);
DISPLAY 1.234043 (-5975 3950);
PAINT GREEN (-5975 3950);
DISPLAY INVISIBLE (-5975 3950);
FORCEPROP 1 LAST HDL_TAP TRUE
J 0
(-5650 3875);
DISPLAY 1.234043 (-5650 3875);
PAINT GREEN (-5650 3875);
DISPLAY INVISIBLE (-5650 3875);
FORCEPROP 1 LAST PATH I110
J 0
(-5977 4000);
DISPLAY 0.872340 (-5977 4000);
PAINT GREEN (-5977 4000);
DISPLAY INVISIBLE (-5977 4000);
FORCEADD TAP..6
(-5975 3950);
FORCEPROP 3 LASTPIN (-5925 3950) SIG_NAME M_H_MA<9>
J 0
(-5915 3960);
DISPLAY 0.659574 (-5915 3960);
PAINT MONO (-5915 3960);
DISPLAY INVISIBLE (-5915 3960);
FORCEPROP 1 LASTPIN (-5925 3950) BN 9
J 0
(-5975 3960);
DISPLAY 0.617021 (-5975 3960);
PAINT PINK (-5975 3960);
FORCEPROP 2 LAST CDS_LIB mstr_standard
J 2
(-5975 3950);
DISPLAY 0.787234 (-5975 3950);
PAINT MONO (-5975 3950);
DISPLAY INVISIBLE (-5975 3950);
FORCEPROP 1 LAST BODY_TYPE PLUMBING
J 0
(-5975 3900);
DISPLAY 1.234043 (-5975 3900);
PAINT GREEN (-5975 3900);
DISPLAY INVISIBLE (-5975 3900);
FORCEPROP 1 LAST HDL_TAP TRUE
J 0
(-5650 3825);
DISPLAY 1.234043 (-5650 3825);
PAINT GREEN (-5650 3825);
DISPLAY INVISIBLE (-5650 3825);
FORCEPROP 1 LAST PATH I111
J 0
(-5977 3950);
DISPLAY 0.872340 (-5977 3950);
PAINT GREEN (-5977 3950);
DISPLAY INVISIBLE (-5977 3950);
FORCEADD TAP..6
(-5975 4050);
FORCEPROP 3 LASTPIN (-5925 4050) SIG_NAME M_H_MA<11>
J 0
(-5915 4060);
DISPLAY 0.659574 (-5915 4060);
PAINT MONO (-5915 4060);
DISPLAY INVISIBLE (-5915 4060);
FORCEPROP 1 LASTPIN (-5925 4050) BN 11
J 0
(-5975 4060);
DISPLAY 0.617021 (-5975 4060);
PAINT PINK (-5975 4060);
FORCEPROP 2 LAST CDS_LIB mstr_standard
J 2
(-5975 4050);
DISPLAY 0.787234 (-5975 4050);
PAINT MONO (-5975 4050);
DISPLAY INVISIBLE (-5975 4050);
FORCEPROP 1 LAST BODY_TYPE PLUMBING
J 0
(-5975 4000);
DISPLAY 1.234043 (-5975 4000);
PAINT GREEN (-5975 4000);
DISPLAY INVISIBLE (-5975 4000);
FORCEPROP 1 LAST HDL_TAP TRUE
J 0
(-5650 3925);
DISPLAY 1.234043 (-5650 3925);
PAINT GREEN (-5650 3925);
DISPLAY INVISIBLE (-5650 3925);
FORCEPROP 1 LAST PATH I112
J 0
(-5977 4050);
DISPLAY 0.872340 (-5977 4050);
PAINT GREEN (-5977 4050);
DISPLAY INVISIBLE (-5977 4050);
FORCEADD TAP..6
(-5975 4100);
FORCEPROP 3 LASTPIN (-5925 4100) SIG_NAME M_H_MA<12>
J 0
(-5915 4110);
DISPLAY 0.659574 (-5915 4110);
PAINT MONO (-5915 4110);
DISPLAY INVISIBLE (-5915 4110);
FORCEPROP 1 LASTPIN (-5925 4100) BN 12
J 0
(-5975 4110);
DISPLAY 0.617021 (-5975 4110);
PAINT PINK (-5975 4110);
FORCEPROP 2 LAST CDS_LIB mstr_standard
J 2
(-5975 4100);
DISPLAY 0.787234 (-5975 4100);
PAINT MONO (-5975 4100);
DISPLAY INVISIBLE (-5975 4100);
FORCEPROP 1 LAST BODY_TYPE PLUMBING
J 0
(-5975 4050);
DISPLAY 1.234043 (-5975 4050);
PAINT GREEN (-5975 4050);
DISPLAY INVISIBLE (-5975 4050);
FORCEPROP 1 LAST HDL_TAP TRUE
J 0
(-5650 3975);
DISPLAY 1.234043 (-5650 3975);
PAINT GREEN (-5650 3975);
DISPLAY INVISIBLE (-5650 3975);
FORCEPROP 1 LAST PATH I113
J 0
(-5977 4100);
DISPLAY 0.872340 (-5977 4100);
PAINT GREEN (-5977 4100);
DISPLAY INVISIBLE (-5977 4100);
FORCEADD TAP..6
(-5975 4150);
FORCEPROP 3 LASTPIN (-5925 4150) SIG_NAME M_H_MA<13>
J 0
(-5915 4160);
DISPLAY 0.659574 (-5915 4160);
PAINT MONO (-5915 4160);
DISPLAY INVISIBLE (-5915 4160);
FORCEPROP 1 LASTPIN (-5925 4150) BN 13
J 0
(-5975 4160);
DISPLAY 0.617021 (-5975 4160);
PAINT PINK (-5975 4160);
FORCEPROP 2 LAST CDS_LIB mstr_standard
J 2
(-5975 4150);
DISPLAY 0.787234 (-5975 4150);
PAINT MONO (-5975 4150);
DISPLAY INVISIBLE (-5975 4150);
FORCEPROP 1 LAST BODY_TYPE PLUMBING
J 0
(-5975 4100);
DISPLAY 1.234043 (-5975 4100);
PAINT GREEN (-5975 4100);
DISPLAY INVISIBLE (-5975 4100);
FORCEPROP 1 LAST HDL_TAP TRUE
J 0
(-5650 4025);
DISPLAY 1.234043 (-5650 4025);
PAINT GREEN (-5650 4025);
DISPLAY INVISIBLE (-5650 4025);
FORCEPROP 1 LAST PATH I114
J 0
(-5977 4150);
DISPLAY 0.872340 (-5977 4150);
PAINT GREEN (-5977 4150);
DISPLAY INVISIBLE (-5977 4150);
FORCEADD TAP..6
(-5975 4250);
FORCEPROP 3 LASTPIN (-5925 4250) SIG_NAME M_H_MA<15>
J 0
(-5915 4260);
DISPLAY 0.659574 (-5915 4260);
PAINT MONO (-5915 4260);
DISPLAY INVISIBLE (-5915 4260);
FORCEPROP 1 LASTPIN (-5925 4250) BN 15
J 0
(-5975 4260);
DISPLAY 0.617021 (-5975 4260);
PAINT PINK (-5975 4260);
FORCEPROP 2 LAST CDS_LIB mstr_standard
J 2
(-5975 4250);
DISPLAY 0.787234 (-5975 4250);
PAINT MONO (-5975 4250);
DISPLAY INVISIBLE (-5975 4250);
FORCEPROP 1 LAST BODY_TYPE PLUMBING
J 0
(-5975 4200);
DISPLAY 1.234043 (-5975 4200);
PAINT GREEN (-5975 4200);
DISPLAY INVISIBLE (-5975 4200);
FORCEPROP 1 LAST HDL_TAP TRUE
J 0
(-5650 4125);
DISPLAY 1.234043 (-5650 4125);
PAINT GREEN (-5650 4125);
DISPLAY INVISIBLE (-5650 4125);
FORCEPROP 1 LAST PATH I115
J 0
(-5977 4250);
DISPLAY 0.872340 (-5977 4250);
PAINT GREEN (-5977 4250);
DISPLAY INVISIBLE (-5977 4250);
FORCEADD TAP..6
(-5975 4200);
FORCEPROP 3 LASTPIN (-5925 4200) SIG_NAME M_H_MA<14>
J 0
(-5915 4210);
DISPLAY 0.659574 (-5915 4210);
PAINT MONO (-5915 4210);
DISPLAY INVISIBLE (-5915 4210);
FORCEPROP 1 LASTPIN (-5925 4200) BN 14
J 0
(-5975 4210);
DISPLAY 0.617021 (-5975 4210);
PAINT PINK (-5975 4210);
FORCEPROP 2 LAST CDS_LIB mstr_standard
J 2
(-5975 4200);
DISPLAY 0.787234 (-5975 4200);
PAINT MONO (-5975 4200);
DISPLAY INVISIBLE (-5975 4200);
FORCEPROP 1 LAST BODY_TYPE PLUMBING
J 0
(-5975 4150);
DISPLAY 1.234043 (-5975 4150);
PAINT GREEN (-5975 4150);
DISPLAY INVISIBLE (-5975 4150);
FORCEPROP 1 LAST HDL_TAP TRUE
J 0
(-5650 4075);
DISPLAY 1.234043 (-5650 4075);
PAINT GREEN (-5650 4075);
DISPLAY INVISIBLE (-5650 4075);
FORCEPROP 1 LAST PATH I116
J 0
(-5977 4200);
DISPLAY 0.872340 (-5977 4200);
PAINT GREEN (-5977 4200);
DISPLAY INVISIBLE (-5977 4200);
FORCEADD TAP..6
(-5975 4300);
FORCEPROP 3 LASTPIN (-5925 4300) SIG_NAME M_H_MA<16>
J 0
(-5915 4310);
DISPLAY 0.659574 (-5915 4310);
PAINT MONO (-5915 4310);
DISPLAY INVISIBLE (-5915 4310);
FORCEPROP 1 LASTPIN (-5925 4300) BN 16
J 0
(-5975 4310);
DISPLAY 0.617021 (-5975 4310);
PAINT PINK (-5975 4310);
FORCEPROP 2 LAST CDS_LIB mstr_standard
J 2
(-5975 4300);
DISPLAY 0.787234 (-5975 4300);
PAINT MONO (-5975 4300);
DISPLAY INVISIBLE (-5975 4300);
FORCEPROP 1 LAST BODY_TYPE PLUMBING
J 0
(-5975 4250);
DISPLAY 1.234043 (-5975 4250);
PAINT GREEN (-5975 4250);
DISPLAY INVISIBLE (-5975 4250);
FORCEPROP 1 LAST HDL_TAP TRUE
J 0
(-5650 4175);
DISPLAY 1.234043 (-5650 4175);
PAINT GREEN (-5650 4175);
DISPLAY INVISIBLE (-5650 4175);
FORCEPROP 1 LAST PATH I117
J 0
(-5977 4300);
DISPLAY 0.872340 (-5977 4300);
PAINT GREEN (-5977 4300);
DISPLAY INVISIBLE (-5977 4300);
FORCEADD TAP..6
(-5975 4350);
FORCEPROP 3 LASTPIN (-5925 4350) SIG_NAME M_H_MA<17>
J 0
(-5915 4360);
DISPLAY 0.659574 (-5915 4360);
PAINT MONO (-5915 4360);
DISPLAY INVISIBLE (-5915 4360);
FORCEPROP 1 LASTPIN (-5925 4350) BN 17
J 0
(-5975 4360);
DISPLAY 0.617021 (-5975 4360);
PAINT PINK (-5975 4360);
FORCEPROP 2 LAST CDS_LIB mstr_standard
J 0
(-5975 4350);
DISPLAY 0.787234 (-5975 4350);
PAINT MONO (-5975 4350);
DISPLAY INVISIBLE (-5975 4350);
FORCEPROP 1 LAST BODY_TYPE PLUMBING
J 0
(-5975 4300);
DISPLAY 1.234043 (-5975 4300);
PAINT GREEN (-5975 4300);
DISPLAY INVISIBLE (-5975 4300);
FORCEPROP 1 LAST HDL_TAP TRUE
J 0
(-5650 4225);
DISPLAY 1.234043 (-5650 4225);
PAINT GREEN (-5650 4225);
DISPLAY INVISIBLE (-5650 4225);
FORCEPROP 1 LAST PATH I118
J 0
(-5977 4350);
DISPLAY 0.872340 (-5977 4350);
PAINT GREEN (-5977 4350);
DISPLAY INVISIBLE (-5977 4350);
FORCEADD TAP..6
R 2
(-4475 3550);
FORCEPROP 3 LASTPIN (-4525 3550) SIG_NAME M_H_DQ<47>
J 0
(-4515 3560);
DISPLAY 0.659574 (-4515 3560);
PAINT MONO (-4515 3560);
DISPLAY INVISIBLE (-4515 3560);
FORCEPROP 1 LASTPIN (-4525 3550) BN 47
J 2
(-4475 3560);
DISPLAY 0.617021 (-4475 3560);
PAINT PINK (-4475 3560);
FORCEPROP 2 LAST CDS_LIB mstr_standard
J 2
(-4475 3550);
DISPLAY 0.787234 (-4475 3550);
PAINT MONO (-4475 3550);
DISPLAY INVISIBLE (-4475 3550);
FORCEPROP 1 LAST BODY_TYPE PLUMBING
J 2
(-4475 3500);
DISPLAY 1.234043 (-4475 3500);
PAINT GREEN (-4475 3500);
DISPLAY INVISIBLE (-4475 3500);
FORCEPROP 1 LAST HDL_TAP TRUE
J 2
(-4800 3425);
DISPLAY 1.234043 (-4800 3425);
PAINT GREEN (-4800 3425);
DISPLAY INVISIBLE (-4800 3425);
FORCEPROP 1 LAST PATH I119
J 2
(-4473 3550);
DISPLAY 0.872340 (-4473 3550);
PAINT GREEN (-4473 3550);
DISPLAY INVISIBLE (-4473 3550);
FORCEADD OFFPAGE..1
(-6625 2250);
FORCEPROP 2 LAST $XR5 82 
J 0
(-7296 2250);
DISPLAY 0.638298 (-7296 2250);
PAINT MONO (-7296 2250);
FORCEPROP 2 LAST $XR4 81 
J 0
(-7206 2250);
DISPLAY 0.638298 (-7206 2250);
PAINT MONO (-7206 2250);
FORCEPROP 2 LAST $XR3 79 
J 0
(-7116 2250);
DISPLAY 0.638298 (-7116 2250);
PAINT MONO (-7116 2250);
FORCEPROP 2 LAST $XR2 78 
J 0
(-7026 2250);
DISPLAY 0.638298 (-7026 2250);
PAINT MONO (-7026 2250);
FORCEPROP 2 LAST $XR1 77 
J 0
(-6936 2250);
DISPLAY 0.638298 (-6936 2250);
PAINT MONO (-6936 2250);
FORCEPROP 2 LAST $XR0 55 
J 0
(-6846 2250);
DISPLAY 0.638298 (-6846 2250);
PAINT MONO (-6846 2250);
FORCEPROP 2 LAST CDS_LIB mstr_standard
J 0
(-6625 2250);
DISPLAY 0.787234 (-6625 2250);
PAINT MONO (-6625 2250);
DISPLAY INVISIBLE (-6625 2250);
FORCEPROP 1 LAST OFFPAGE TRUE
J 0
(-6300 2125);
DISPLAY 0.936170 (-6300 2125);
PAINT GREEN (-6300 2125);
DISPLAY INVISIBLE (-6300 2125);
FORCEPROP 1 LAST COMMENT_BODY TRUE
J 0
(-6500 2150);
DISPLAY 0.936170 (-6500 2150);
PAINT GREEN (-6500 2150);
DISPLAY INVISIBLE (-6500 2150);
FORCEPROP 2 LAST PATH I12
J 0
(-6875 2300);
DISPLAY 1.021277 (-6875 2300);
PAINT ORANGE (-6875 2300);
DISPLAY INVISIBLE (-6875 2300);
FORCEADD TAP..6
R 2
(-4475 3600);
FORCEPROP 3 LASTPIN (-4525 3600) SIG_NAME M_H_DQ<48>
J 0
(-4515 3610);
DISPLAY 0.659574 (-4515 3610);
PAINT MONO (-4515 3610);
DISPLAY INVISIBLE (-4515 3610);
FORCEPROP 1 LASTPIN (-4525 3600) BN 48
J 2
(-4475 3610);
DISPLAY 0.617021 (-4475 3610);
PAINT PINK (-4475 3610);
FORCEPROP 2 LAST CDS_LIB mstr_standard
J 2
(-4475 3600);
DISPLAY 0.787234 (-4475 3600);
PAINT MONO (-4475 3600);
DISPLAY INVISIBLE (-4475 3600);
FORCEPROP 1 LAST BODY_TYPE PLUMBING
J 2
(-4475 3550);
DISPLAY 1.234043 (-4475 3550);
PAINT GREEN (-4475 3550);
DISPLAY INVISIBLE (-4475 3550);
FORCEPROP 1 LAST HDL_TAP TRUE
J 2
(-4800 3475);
DISPLAY 1.234043 (-4800 3475);
PAINT GREEN (-4800 3475);
DISPLAY INVISIBLE (-4800 3475);
FORCEPROP 1 LAST PATH I120
J 2
(-4473 3600);
DISPLAY 0.872340 (-4473 3600);
PAINT GREEN (-4473 3600);
DISPLAY INVISIBLE (-4473 3600);
FORCEADD TAP..6
R 2
(-4475 3650);
FORCEPROP 3 LASTPIN (-4525 3650) SIG_NAME M_H_DQ<49>
J 0
(-4515 3660);
DISPLAY 0.659574 (-4515 3660);
PAINT MONO (-4515 3660);
DISPLAY INVISIBLE (-4515 3660);
FORCEPROP 1 LASTPIN (-4525 3650) BN 49
J 2
(-4475 3660);
DISPLAY 0.617021 (-4475 3660);
PAINT PINK (-4475 3660);
FORCEPROP 2 LAST CDS_LIB mstr_standard
J 2
(-4475 3650);
DISPLAY 0.787234 (-4475 3650);
PAINT MONO (-4475 3650);
DISPLAY INVISIBLE (-4475 3650);
FORCEPROP 1 LAST BODY_TYPE PLUMBING
J 2
(-4475 3600);
DISPLAY 1.234043 (-4475 3600);
PAINT GREEN (-4475 3600);
DISPLAY INVISIBLE (-4475 3600);
FORCEPROP 1 LAST HDL_TAP TRUE
J 2
(-4800 3525);
DISPLAY 1.234043 (-4800 3525);
PAINT GREEN (-4800 3525);
DISPLAY INVISIBLE (-4800 3525);
FORCEPROP 1 LAST PATH I121
J 2
(-4473 3650);
DISPLAY 0.872340 (-4473 3650);
PAINT GREEN (-4473 3650);
DISPLAY INVISIBLE (-4473 3650);
FORCEADD TAP..6
R 2
(-4475 3800);
FORCEPROP 3 LASTPIN (-4525 3800) SIG_NAME M_H_DQ<52>
J 0
(-4515 3810);
DISPLAY 0.659574 (-4515 3810);
PAINT MONO (-4515 3810);
DISPLAY INVISIBLE (-4515 3810);
FORCEPROP 1 LASTPIN (-4525 3800) BN 52
J 2
(-4475 3810);
DISPLAY 0.617021 (-4475 3810);
PAINT PINK (-4475 3810);
FORCEPROP 2 LAST CDS_LIB mstr_standard
J 2
(-4475 3800);
DISPLAY 0.787234 (-4475 3800);
PAINT MONO (-4475 3800);
DISPLAY INVISIBLE (-4475 3800);
FORCEPROP 1 LAST BODY_TYPE PLUMBING
J 2
(-4475 3750);
DISPLAY 1.234043 (-4475 3750);
PAINT GREEN (-4475 3750);
DISPLAY INVISIBLE (-4475 3750);
FORCEPROP 1 LAST HDL_TAP TRUE
J 2
(-4800 3675);
DISPLAY 1.234043 (-4800 3675);
PAINT GREEN (-4800 3675);
DISPLAY INVISIBLE (-4800 3675);
FORCEPROP 1 LAST PATH I122
J 2
(-4473 3800);
DISPLAY 0.872340 (-4473 3800);
PAINT GREEN (-4473 3800);
DISPLAY INVISIBLE (-4473 3800);
FORCEADD TAP..6
R 2
(-4475 3700);
FORCEPROP 3 LASTPIN (-4525 3700) SIG_NAME M_H_DQ<50>
J 0
(-4515 3710);
DISPLAY 0.659574 (-4515 3710);
PAINT MONO (-4515 3710);
DISPLAY INVISIBLE (-4515 3710);
FORCEPROP 1 LASTPIN (-4525 3700) BN 50
J 2
(-4475 3710);
DISPLAY 0.617021 (-4475 3710);
PAINT PINK (-4475 3710);
FORCEPROP 2 LAST CDS_LIB mstr_standard
J 2
(-4475 3700);
DISPLAY 0.787234 (-4475 3700);
PAINT MONO (-4475 3700);
DISPLAY INVISIBLE (-4475 3700);
FORCEPROP 1 LAST BODY_TYPE PLUMBING
J 2
(-4475 3650);
DISPLAY 1.234043 (-4475 3650);
PAINT GREEN (-4475 3650);
DISPLAY INVISIBLE (-4475 3650);
FORCEPROP 1 LAST HDL_TAP TRUE
J 2
(-4800 3575);
DISPLAY 1.234043 (-4800 3575);
PAINT GREEN (-4800 3575);
DISPLAY INVISIBLE (-4800 3575);
FORCEPROP 1 LAST PATH I123
J 2
(-4473 3700);
DISPLAY 0.872340 (-4473 3700);
PAINT GREEN (-4473 3700);
DISPLAY INVISIBLE (-4473 3700);
FORCEADD TAP..6
R 2
(-4475 3750);
FORCEPROP 3 LASTPIN (-4525 3750) SIG_NAME M_H_DQ<51>
J 0
(-4515 3760);
DISPLAY 0.659574 (-4515 3760);
PAINT MONO (-4515 3760);
DISPLAY INVISIBLE (-4515 3760);
FORCEPROP 1 LASTPIN (-4525 3750) BN 51
J 2
(-4475 3760);
DISPLAY 0.617021 (-4475 3760);
PAINT PINK (-4475 3760);
FORCEPROP 2 LAST CDS_LIB mstr_standard
J 2
(-4475 3750);
DISPLAY 0.787234 (-4475 3750);
PAINT MONO (-4475 3750);
DISPLAY INVISIBLE (-4475 3750);
FORCEPROP 1 LAST BODY_TYPE PLUMBING
J 2
(-4475 3700);
DISPLAY 1.234043 (-4475 3700);
PAINT GREEN (-4475 3700);
DISPLAY INVISIBLE (-4475 3700);
FORCEPROP 1 LAST HDL_TAP TRUE
J 2
(-4800 3625);
DISPLAY 1.234043 (-4800 3625);
PAINT GREEN (-4800 3625);
DISPLAY INVISIBLE (-4800 3625);
FORCEPROP 1 LAST PATH I124
J 2
(-4473 3750);
DISPLAY 0.872340 (-4473 3750);
PAINT GREEN (-4473 3750);
DISPLAY INVISIBLE (-4473 3750);
FORCEADD TAP..6
R 2
(-4475 3850);
FORCEPROP 3 LASTPIN (-4525 3850) SIG_NAME M_H_DQ<53>
J 0
(-4515 3860);
DISPLAY 0.659574 (-4515 3860);
PAINT MONO (-4515 3860);
DISPLAY INVISIBLE (-4515 3860);
FORCEPROP 1 LASTPIN (-4525 3850) BN 53
J 2
(-4475 3860);
DISPLAY 0.617021 (-4475 3860);
PAINT PINK (-4475 3860);
FORCEPROP 2 LAST CDS_LIB mstr_standard
J 2
(-4475 3850);
DISPLAY 0.787234 (-4475 3850);
PAINT MONO (-4475 3850);
DISPLAY INVISIBLE (-4475 3850);
FORCEPROP 1 LAST BODY_TYPE PLUMBING
J 2
(-4475 3800);
DISPLAY 1.234043 (-4475 3800);
PAINT GREEN (-4475 3800);
DISPLAY INVISIBLE (-4475 3800);
FORCEPROP 1 LAST HDL_TAP TRUE
J 2
(-4800 3725);
DISPLAY 1.234043 (-4800 3725);
PAINT GREEN (-4800 3725);
DISPLAY INVISIBLE (-4800 3725);
FORCEPROP 1 LAST PATH I125
J 2
(-4473 3850);
DISPLAY 0.872340 (-4473 3850);
PAINT GREEN (-4473 3850);
DISPLAY INVISIBLE (-4473 3850);
FORCEADD TAP..6
R 2
(-4475 3900);
FORCEPROP 3 LASTPIN (-4525 3900) SIG_NAME M_H_DQ<54>
J 0
(-4515 3910);
DISPLAY 0.659574 (-4515 3910);
PAINT MONO (-4515 3910);
DISPLAY INVISIBLE (-4515 3910);
FORCEPROP 1 LASTPIN (-4525 3900) BN 54
J 2
(-4475 3910);
DISPLAY 0.617021 (-4475 3910);
PAINT PINK (-4475 3910);
FORCEPROP 2 LAST CDS_LIB mstr_standard
J 2
(-4475 3900);
DISPLAY 0.787234 (-4475 3900);
PAINT MONO (-4475 3900);
DISPLAY INVISIBLE (-4475 3900);
FORCEPROP 1 LAST BODY_TYPE PLUMBING
J 2
(-4475 3850);
DISPLAY 1.234043 (-4475 3850);
PAINT GREEN (-4475 3850);
DISPLAY INVISIBLE (-4475 3850);
FORCEPROP 1 LAST HDL_TAP TRUE
J 2
(-4800 3775);
DISPLAY 1.234043 (-4800 3775);
PAINT GREEN (-4800 3775);
DISPLAY INVISIBLE (-4800 3775);
FORCEPROP 1 LAST PATH I126
J 2
(-4473 3900);
DISPLAY 0.872340 (-4473 3900);
PAINT GREEN (-4473 3900);
DISPLAY INVISIBLE (-4473 3900);
FORCEADD TAP..6
R 2
(-4475 4050);
FORCEPROP 3 LASTPIN (-4525 4050) SIG_NAME M_H_DQ<57>
J 0
(-4515 4060);
DISPLAY 0.659574 (-4515 4060);
PAINT MONO (-4515 4060);
DISPLAY INVISIBLE (-4515 4060);
FORCEPROP 1 LASTPIN (-4525 4050) BN 57
J 2
(-4475 4060);
DISPLAY 0.617021 (-4475 4060);
PAINT PINK (-4475 4060);
FORCEPROP 2 LAST CDS_LIB mstr_standard
J 2
(-4475 4050);
DISPLAY 0.787234 (-4475 4050);
PAINT MONO (-4475 4050);
DISPLAY INVISIBLE (-4475 4050);
FORCEPROP 1 LAST BODY_TYPE PLUMBING
J 2
(-4475 4000);
DISPLAY 1.234043 (-4475 4000);
PAINT GREEN (-4475 4000);
DISPLAY INVISIBLE (-4475 4000);
FORCEPROP 1 LAST HDL_TAP TRUE
J 2
(-4800 3925);
DISPLAY 1.234043 (-4800 3925);
PAINT GREEN (-4800 3925);
DISPLAY INVISIBLE (-4800 3925);
FORCEPROP 1 LAST PATH I127
J 2
(-4473 4050);
DISPLAY 0.872340 (-4473 4050);
PAINT GREEN (-4473 4050);
DISPLAY INVISIBLE (-4473 4050);
FORCEADD TAP..6
R 2
(-4475 3950);
FORCEPROP 3 LASTPIN (-4525 3950) SIG_NAME M_H_DQ<55>
J 0
(-4515 3960);
DISPLAY 0.659574 (-4515 3960);
PAINT MONO (-4515 3960);
DISPLAY INVISIBLE (-4515 3960);
FORCEPROP 1 LASTPIN (-4525 3950) BN 55
J 2
(-4475 3960);
DISPLAY 0.617021 (-4475 3960);
PAINT PINK (-4475 3960);
FORCEPROP 2 LAST CDS_LIB mstr_standard
J 2
(-4475 3950);
DISPLAY 0.787234 (-4475 3950);
PAINT MONO (-4475 3950);
DISPLAY INVISIBLE (-4475 3950);
FORCEPROP 1 LAST BODY_TYPE PLUMBING
J 2
(-4475 3900);
DISPLAY 1.234043 (-4475 3900);
PAINT GREEN (-4475 3900);
DISPLAY INVISIBLE (-4475 3900);
FORCEPROP 1 LAST HDL_TAP TRUE
J 2
(-4800 3825);
DISPLAY 1.234043 (-4800 3825);
PAINT GREEN (-4800 3825);
DISPLAY INVISIBLE (-4800 3825);
FORCEPROP 1 LAST PATH I128
J 2
(-4473 3950);
DISPLAY 0.872340 (-4473 3950);
PAINT GREEN (-4473 3950);
DISPLAY INVISIBLE (-4473 3950);
FORCEADD TAP..6
R 2
(-4475 4000);
FORCEPROP 3 LASTPIN (-4525 4000) SIG_NAME M_H_DQ<56>
J 0
(-4515 4010);
DISPLAY 0.659574 (-4515 4010);
PAINT MONO (-4515 4010);
DISPLAY INVISIBLE (-4515 4010);
FORCEPROP 1 LASTPIN (-4525 4000) BN 56
J 2
(-4475 4010);
DISPLAY 0.617021 (-4475 4010);
PAINT PINK (-4475 4010);
FORCEPROP 2 LAST CDS_LIB mstr_standard
J 2
(-4475 4000);
DISPLAY 0.787234 (-4475 4000);
PAINT MONO (-4475 4000);
DISPLAY INVISIBLE (-4475 4000);
FORCEPROP 1 LAST BODY_TYPE PLUMBING
J 2
(-4475 3950);
DISPLAY 1.234043 (-4475 3950);
PAINT GREEN (-4475 3950);
DISPLAY INVISIBLE (-4475 3950);
FORCEPROP 1 LAST HDL_TAP TRUE
J 2
(-4800 3875);
DISPLAY 1.234043 (-4800 3875);
PAINT GREEN (-4800 3875);
DISPLAY INVISIBLE (-4800 3875);
FORCEPROP 1 LAST PATH I129
J 2
(-4473 4000);
DISPLAY 0.872340 (-4473 4000);
PAINT GREEN (-4473 4000);
DISPLAY INVISIBLE (-4473 4000);
FORCEADD OFFPAGE..6
(-6625 2350);
FORCEPROP 2 LAST $XR1 79 
J 0
(-6964 2350);
DISPLAY 0.638298 (-6964 2350);
PAINT MONO (-6964 2350);
FORCEPROP 2 LAST $XR0 58 
J 0
(-6874 2350);
DISPLAY 0.638298 (-6874 2350);
PAINT MONO (-6874 2350);
FORCEPROP 2 LAST CDS_LIB mstr_standard
J 0
(-6625 2350);
DISPLAY 0.787234 (-6625 2350);
PAINT MONO (-6625 2350);
DISPLAY INVISIBLE (-6625 2350);
FORCEPROP 1 LAST OFFPAGE TRUE
J 0
(-6300 2225);
DISPLAY 0.936170 (-6300 2225);
PAINT GREEN (-6300 2225);
DISPLAY INVISIBLE (-6300 2225);
FORCEPROP 1 LAST COMMENT_BODY TRUE
J 0
(-6525 2275);
DISPLAY 0.936170 (-6525 2275);
PAINT GREEN (-6525 2275);
DISPLAY INVISIBLE (-6525 2275);
FORCEPROP 2 LAST PATH I13
J 0
(-6850 2400);
DISPLAY 1.021277 (-6850 2400);
PAINT ORANGE (-6850 2400);
DISPLAY INVISIBLE (-6850 2400);
FORCEADD TAP..6
R 2
(-4475 4150);
FORCEPROP 3 LASTPIN (-4525 4150) SIG_NAME M_H_DQ<59>
J 0
(-4515 4160);
DISPLAY 0.659574 (-4515 4160);
PAINT MONO (-4515 4160);
DISPLAY INVISIBLE (-4515 4160);
FORCEPROP 1 LASTPIN (-4525 4150) BN 59
J 2
(-4475 4160);
DISPLAY 0.617021 (-4475 4160);
PAINT PINK (-4475 4160);
FORCEPROP 2 LAST CDS_LIB mstr_standard
J 2
(-4475 4150);
DISPLAY 0.787234 (-4475 4150);
PAINT MONO (-4475 4150);
DISPLAY INVISIBLE (-4475 4150);
FORCEPROP 1 LAST BODY_TYPE PLUMBING
J 2
(-4475 4100);
DISPLAY 1.234043 (-4475 4100);
PAINT GREEN (-4475 4100);
DISPLAY INVISIBLE (-4475 4100);
FORCEPROP 1 LAST HDL_TAP TRUE
J 2
(-4800 4025);
DISPLAY 1.234043 (-4800 4025);
PAINT GREEN (-4800 4025);
DISPLAY INVISIBLE (-4800 4025);
FORCEPROP 1 LAST PATH I130
J 2
(-4473 4150);
DISPLAY 0.872340 (-4473 4150);
PAINT GREEN (-4473 4150);
DISPLAY INVISIBLE (-4473 4150);
FORCEADD TAP..6
R 2
(-4475 4100);
FORCEPROP 3 LASTPIN (-4525 4100) SIG_NAME M_H_DQ<58>
J 0
(-4515 4110);
DISPLAY 0.659574 (-4515 4110);
PAINT MONO (-4515 4110);
DISPLAY INVISIBLE (-4515 4110);
FORCEPROP 1 LASTPIN (-4525 4100) BN 58
J 2
(-4475 4110);
DISPLAY 0.617021 (-4475 4110);
PAINT PINK (-4475 4110);
FORCEPROP 2 LAST CDS_LIB mstr_standard
J 2
(-4475 4100);
DISPLAY 0.787234 (-4475 4100);
PAINT MONO (-4475 4100);
DISPLAY INVISIBLE (-4475 4100);
FORCEPROP 1 LAST BODY_TYPE PLUMBING
J 2
(-4475 4050);
DISPLAY 1.234043 (-4475 4050);
PAINT GREEN (-4475 4050);
DISPLAY INVISIBLE (-4475 4050);
FORCEPROP 1 LAST HDL_TAP TRUE
J 2
(-4800 3975);
DISPLAY 1.234043 (-4800 3975);
PAINT GREEN (-4800 3975);
DISPLAY INVISIBLE (-4800 3975);
FORCEPROP 1 LAST PATH I131
J 2
(-4473 4100);
DISPLAY 0.872340 (-4473 4100);
PAINT GREEN (-4473 4100);
DISPLAY INVISIBLE (-4473 4100);
FORCEADD TAP..6
R 2
(-4475 4300);
FORCEPROP 3 LASTPIN (-4525 4300) SIG_NAME M_H_DQ<62>
J 0
(-4515 4310);
DISPLAY 0.659574 (-4515 4310);
PAINT MONO (-4515 4310);
DISPLAY INVISIBLE (-4515 4310);
FORCEPROP 1 LASTPIN (-4525 4300) BN 62
J 2
(-4475 4310);
DISPLAY 0.617021 (-4475 4310);
PAINT PINK (-4475 4310);
FORCEPROP 2 LAST CDS_LIB mstr_standard
J 2
(-4475 4300);
DISPLAY 0.787234 (-4475 4300);
PAINT MONO (-4475 4300);
DISPLAY INVISIBLE (-4475 4300);
FORCEPROP 1 LAST BODY_TYPE PLUMBING
J 2
(-4475 4250);
DISPLAY 1.234043 (-4475 4250);
PAINT GREEN (-4475 4250);
DISPLAY INVISIBLE (-4475 4250);
FORCEPROP 1 LAST HDL_TAP TRUE
J 2
(-4800 4175);
DISPLAY 1.234043 (-4800 4175);
PAINT GREEN (-4800 4175);
DISPLAY INVISIBLE (-4800 4175);
FORCEPROP 1 LAST PATH I132
J 2
(-4473 4300);
DISPLAY 0.872340 (-4473 4300);
PAINT GREEN (-4473 4300);
DISPLAY INVISIBLE (-4473 4300);
FORCEADD TAP..6
R 2
(-4475 4200);
FORCEPROP 3 LASTPIN (-4525 4200) SIG_NAME M_H_DQ<60>
J 0
(-4515 4210);
DISPLAY 0.659574 (-4515 4210);
PAINT MONO (-4515 4210);
DISPLAY INVISIBLE (-4515 4210);
FORCEPROP 1 LASTPIN (-4525 4200) BN 60
J 2
(-4475 4210);
DISPLAY 0.617021 (-4475 4210);
PAINT PINK (-4475 4210);
FORCEPROP 2 LAST CDS_LIB mstr_standard
J 2
(-4475 4200);
DISPLAY 0.787234 (-4475 4200);
PAINT MONO (-4475 4200);
DISPLAY INVISIBLE (-4475 4200);
FORCEPROP 1 LAST BODY_TYPE PLUMBING
J 2
(-4475 4150);
DISPLAY 1.234043 (-4475 4150);
PAINT GREEN (-4475 4150);
DISPLAY INVISIBLE (-4475 4150);
FORCEPROP 1 LAST HDL_TAP TRUE
J 2
(-4800 4075);
DISPLAY 1.234043 (-4800 4075);
PAINT GREEN (-4800 4075);
DISPLAY INVISIBLE (-4800 4075);
FORCEPROP 1 LAST PATH I133
J 2
(-4473 4200);
DISPLAY 0.872340 (-4473 4200);
PAINT GREEN (-4473 4200);
DISPLAY INVISIBLE (-4473 4200);
FORCEADD TAP..6
R 2
(-4475 4250);
FORCEPROP 3 LASTPIN (-4525 4250) SIG_NAME M_H_DQ<61>
J 0
(-4515 4260);
DISPLAY 0.659574 (-4515 4260);
PAINT MONO (-4515 4260);
DISPLAY INVISIBLE (-4515 4260);
FORCEPROP 1 LASTPIN (-4525 4250) BN 61
J 2
(-4475 4260);
DISPLAY 0.617021 (-4475 4260);
PAINT PINK (-4475 4260);
FORCEPROP 2 LAST CDS_LIB mstr_standard
J 2
(-4475 4250);
DISPLAY 0.787234 (-4475 4250);
PAINT MONO (-4475 4250);
DISPLAY INVISIBLE (-4475 4250);
FORCEPROP 1 LAST BODY_TYPE PLUMBING
J 2
(-4475 4200);
DISPLAY 1.234043 (-4475 4200);
PAINT GREEN (-4475 4200);
DISPLAY INVISIBLE (-4475 4200);
FORCEPROP 1 LAST HDL_TAP TRUE
J 2
(-4800 4125);
DISPLAY 1.234043 (-4800 4125);
PAINT GREEN (-4800 4125);
DISPLAY INVISIBLE (-4800 4125);
FORCEPROP 1 LAST PATH I134
J 2
(-4473 4250);
DISPLAY 0.872340 (-4473 4250);
PAINT GREEN (-4473 4250);
DISPLAY INVISIBLE (-4473 4250);
FORCEADD TAP..6
R 2
(-4475 4350);
FORCEPROP 3 LASTPIN (-4525 4350) SIG_NAME M_H_DQ<63>
J 0
(-4515 4360);
DISPLAY 0.659574 (-4515 4360);
PAINT MONO (-4515 4360);
DISPLAY INVISIBLE (-4515 4360);
FORCEPROP 1 LASTPIN (-4525 4350) BN 63
J 2
(-4475 4360);
DISPLAY 0.617021 (-4475 4360);
PAINT PINK (-4475 4360);
FORCEPROP 2 LAST CDS_LIB mstr_standard
J 2
(-4475 4350);
DISPLAY 0.787234 (-4475 4350);
PAINT MONO (-4475 4350);
DISPLAY INVISIBLE (-4475 4350);
FORCEPROP 1 LAST BODY_TYPE PLUMBING
J 2
(-4475 4300);
DISPLAY 1.234043 (-4475 4300);
PAINT GREEN (-4475 4300);
DISPLAY INVISIBLE (-4475 4300);
FORCEPROP 1 LAST HDL_TAP TRUE
J 2
(-4800 4225);
DISPLAY 1.234043 (-4800 4225);
PAINT GREEN (-4800 4225);
DISPLAY INVISIBLE (-4800 4225);
FORCEPROP 1 LAST PATH I135
J 2
(-4473 4350);
DISPLAY 0.872340 (-4473 4350);
PAINT GREEN (-4473 4350);
DISPLAY INVISIBLE (-4473 4350);
FORCEADD OFFPAGE..3
(-3875 4400);
FORCEPROP 2 LAST $XR1 79 
J 0
(-3571 4400);
DISPLAY 0.638298 (-3571 4400);
PAINT MONO (-3571 4400);
FORCEPROP 2 LAST $XR0 58 
J 0
(-3661 4400);
DISPLAY 0.638298 (-3661 4400);
PAINT MONO (-3661 4400);
FORCEPROP 2 LAST CDS_LIB mstr_standard
J 0
(-3875 4400);
DISPLAY 0.787234 (-3875 4400);
PAINT MONO (-3875 4400);
DISPLAY INVISIBLE (-3875 4400);
FORCEPROP 1 LAST OFFPAGE TRUE
J 0
(-3550 4275);
DISPLAY 0.936170 (-3550 4275);
PAINT GREEN (-3550 4275);
DISPLAY INVISIBLE (-3550 4275);
FORCEPROP 1 LAST COMMENT_BODY TRUE
J 0
(-3925 4300);
DISPLAY 0.936170 (-3925 4300);
PAINT GREEN (-3925 4300);
DISPLAY INVISIBLE (-3925 4300);
FORCEPROP 2 LAST PATH I136
J 0
(-3650 4450);
DISPLAY 1.021277 (-3650 4450);
PAINT ORANGE (-3650 4450);
DISPLAY INVISIBLE (-3650 4450);
FORCEADD GND..1
R 2
(-1575 550);
FORCEPROP 3 LASTPIN (-1575 600) SIG_NAME GND\g
J 0
(-1565 610);
DISPLAY 0.659574 (-1565 610);
PAINT MONO (-1565 610);
DISPLAY INVISIBLE (-1565 610);
FORCEPROP 1 LAST VOLTAGE 0
J 0
(-1575 550);
PAINT SKYBLUE (-1575 550);
DISPLAY INVISIBLE (-1575 550);
FORCEPROP 2 LAST CDS_LIB mstr_symbols
J 0
(-1575 550);
DISPLAY 0.787234 (-1575 550);
PAINT MONO (-1575 550);
DISPLAY INVISIBLE (-1575 550);
FORCEPROP 1 LAST SIZE 1B
J 2
(-1650 500);
DISPLAY 1.170213 (-1650 500);
PAINT GREEN (-1650 500);
DISPLAY INVISIBLE (-1650 500);
FORCEPROP 2 LAST BOM_COST MEM
J 0
(-1575 555);
PAINT ORANGE (-1575 555);
DISPLAY INVISIBLE (-1575 555);
FORCEPROP 1 LAST BODY_TYPE PLUMBING
J 2
(-1530 507);
DISPLAY 0.340426 (-1530 507);
PAINT GREEN (-1530 507);
DISPLAY INVISIBLE (-1530 507);
FORCEPROP 1 LAST PATH I137
J 2
(-1650 550);
DISPLAY 0.872340 (-1650 550);
PAINT AQUA (-1650 550);
DISPLAY INVISIBLE (-1650 550);
FORCEPROP 2 LAST ROOM DDR4_GH_G
J 0
(-1575 555);
PAINT ORANGE (-1575 555);
DISPLAY INVISIBLE (-1575 555);
FORCEPROP 1 LAST HDL_POWER GND
J 2
(-1575 700);
DISPLAY 0.553191 (-1575 700);
PAINT GREEN (-1575 700);
DISPLAY INVISIBLE (-1575 700);
FORCEADD SCONN288_H44441003..3
(-875 1850);
FORCEPROP 1 LAST LOCATION J9U1
J 0
(-1325 3250);
DISPLAY 0.617021 (-1325 3250);
PAINT AQUA (-1325 3250);
FORCEPROP 1 LAST PART_NUMBER H44441-003
J 0
(-1325 500);
DISPLAY 0.617021 (-1325 500);
PAINT BLUE (-1325 500);
FORCEPROP 1 LAST MATERIAL SCONN
J 0
(-1325 3200);
DISPLAY 0.617021 (-1325 3200);
PAINT SKYBLUE (-1325 3200);
FORCEPROP 2 LASTPIN (-1375 3000) $PN 2
J 2
(-1385 3010);
DISPLAY 0.617021 (-1385 3010);
PAINT ORANGE (-1385 3010);
FORCEPROP 2 LASTPIN (-1375 2950) $PN 4
J 2
(-1385 2960);
DISPLAY 0.617021 (-1385 2960);
PAINT ORANGE (-1385 2960);
FORCEPROP 2 LASTPIN (-1375 2900) $PN 6
J 2
(-1385 2910);
DISPLAY 0.617021 (-1385 2910);
PAINT ORANGE (-1385 2910);
FORCEPROP 2 LASTPIN (-1375 2850) $PN 9
J 2
(-1385 2860);
DISPLAY 0.617021 (-1385 2860);
PAINT ORANGE (-1385 2860);
FORCEPROP 2 LASTPIN (-1375 2750) $PN 13
J 2
(-1385 2760);
DISPLAY 0.617021 (-1385 2760);
PAINT ORANGE (-1385 2760);
FORCEPROP 2 LASTPIN (-1375 2700) $PN 15
J 2
(-1385 2710);
DISPLAY 0.617021 (-1385 2710);
PAINT ORANGE (-1385 2710);
FORCEPROP 2 LASTPIN (-1375 2650) $PN 17
J 2
(-1385 2660);
DISPLAY 0.617021 (-1385 2660);
PAINT ORANGE (-1385 2660);
FORCEPROP 2 LASTPIN (-1375 2600) $PN 20
J 2
(-1385 2610);
DISPLAY 0.617021 (-1385 2610);
PAINT ORANGE (-1385 2610);
FORCEPROP 2 LASTPIN (-1375 2550) $PN 22
J 2
(-1385 2560);
DISPLAY 0.617021 (-1385 2560);
PAINT ORANGE (-1385 2560);
FORCEPROP 2 LASTPIN (-1375 2500) $PN 24
J 2
(-1385 2510);
DISPLAY 0.617021 (-1385 2510);
PAINT ORANGE (-1385 2510);
FORCEPROP 2 LASTPIN (-1375 2450) $PN 26
J 2
(-1385 2460);
DISPLAY 0.617021 (-1385 2460);
PAINT ORANGE (-1385 2460);
FORCEPROP 2 LASTPIN (-1375 2400) $PN 28
J 2
(-1385 2410);
DISPLAY 0.617021 (-1385 2410);
PAINT ORANGE (-1385 2410);
FORCEPROP 2 LASTPIN (-1375 2350) $PN 31
J 2
(-1385 2360);
DISPLAY 0.617021 (-1385 2360);
PAINT ORANGE (-1385 2360);
FORCEPROP 2 LASTPIN (-1375 2250) $PN 35
J 2
(-1385 2260);
DISPLAY 0.617021 (-1385 2260);
PAINT ORANGE (-1385 2260);
FORCEPROP 2 LASTPIN (-1375 2200) $PN 37
J 2
(-1385 2210);
DISPLAY 0.617021 (-1385 2210);
PAINT ORANGE (-1385 2210);
FORCEPROP 2 LASTPIN (-1375 2150) $PN 39
J 2
(-1385 2160);
DISPLAY 0.617021 (-1385 2160);
PAINT ORANGE (-1385 2160);
FORCEPROP 2 LASTPIN (-1375 2100) $PN 42
J 2
(-1385 2110);
DISPLAY 0.617021 (-1385 2110);
PAINT ORANGE (-1385 2110);
FORCEPROP 2 LASTPIN (-1375 2050) $PN 44
J 2
(-1385 2060);
DISPLAY 0.617021 (-1385 2060);
PAINT ORANGE (-1385 2060);
FORCEPROP 2 LASTPIN (-1375 2000) $PN 46
J 2
(-1385 2010);
DISPLAY 0.617021 (-1385 2010);
PAINT ORANGE (-1385 2010);
FORCEPROP 2 LASTPIN (-1375 1950) $PN 48
J 2
(-1385 1960);
DISPLAY 0.617021 (-1385 1960);
PAINT ORANGE (-1385 1960);
FORCEPROP 2 LASTPIN (-1375 1900) $PN 50
J 2
(-1385 1910);
DISPLAY 0.617021 (-1385 1910);
PAINT ORANGE (-1385 1910);
FORCEPROP 2 LASTPIN (-1375 1850) $PN 53
J 2
(-1385 1860);
DISPLAY 0.617021 (-1385 1860);
PAINT ORANGE (-1385 1860);
FORCEPROP 2 LASTPIN (-1375 1800) $PN 55
J 2
(-1385 1810);
DISPLAY 0.617021 (-1385 1810);
PAINT ORANGE (-1385 1810);
FORCEPROP 2 LASTPIN (-1375 1750) $PN 57
J 2
(-1385 1760);
DISPLAY 0.617021 (-1385 1760);
PAINT ORANGE (-1385 1760);
FORCEPROP 2 LASTPIN (-1375 1700) $PN 94
J 2
(-1385 1710);
DISPLAY 0.617021 (-1385 1710);
PAINT ORANGE (-1385 1710);
FORCEPROP 2 LASTPIN (-1375 1650) $PN 96
J 2
(-1385 1660);
DISPLAY 0.617021 (-1385 1660);
PAINT ORANGE (-1385 1660);
FORCEPROP 2 LASTPIN (-1375 1600) $PN 98
J 2
(-1385 1610);
DISPLAY 0.617021 (-1385 1610);
PAINT ORANGE (-1385 1610);
FORCEPROP 2 LASTPIN (-1375 1550) $PN 101
J 2
(-1385 1560);
DISPLAY 0.617021 (-1385 1560);
PAINT ORANGE (-1385 1560);
FORCEPROP 2 LASTPIN (-1375 1400) $PN 107
J 2
(-1385 1410);
DISPLAY 0.617021 (-1385 1410);
PAINT ORANGE (-1385 1410);
FORCEPROP 2 LASTPIN (-1375 1350) $PN 109
J 2
(-1385 1360);
DISPLAY 0.617021 (-1385 1360);
PAINT ORANGE (-1385 1360);
FORCEPROP 2 LASTPIN (-1375 1300) $PN 112
J 2
(-1385 1310);
DISPLAY 0.617021 (-1385 1310);
PAINT ORANGE (-1385 1310);
FORCEPROP 2 LASTPIN (-1375 1250) $PN 114
J 2
(-1385 1260);
DISPLAY 0.617021 (-1385 1260);
PAINT ORANGE (-1385 1260);
FORCEPROP 2 LASTPIN (-1375 1200) $PN 116
J 2
(-1385 1210);
DISPLAY 0.617021 (-1385 1210);
PAINT ORANGE (-1385 1210);
FORCEPROP 2 LASTPIN (-1375 1150) $PN 118
J 2
(-1385 1160);
DISPLAY 0.617021 (-1385 1160);
PAINT ORANGE (-1385 1160);
FORCEPROP 2 LASTPIN (-1375 1100) $PN 120
J 2
(-1385 1110);
DISPLAY 0.617021 (-1385 1110);
PAINT ORANGE (-1385 1110);
FORCEPROP 2 LASTPIN (-1375 1050) $PN 123
J 2
(-1385 1060);
DISPLAY 0.617021 (-1385 1060);
PAINT ORANGE (-1385 1060);
FORCEPROP 2 LASTPIN (-1375 1000) $PN 125
J 2
(-1385 1010);
DISPLAY 0.617021 (-1385 1010);
PAINT ORANGE (-1385 1010);
FORCEPROP 2 LASTPIN (-1375 950) $PN 127
J 2
(-1385 960);
DISPLAY 0.617021 (-1385 960);
PAINT ORANGE (-1385 960);
FORCEPROP 2 LASTPIN (-1375 900) $PN 129
J 2
(-1385 910);
DISPLAY 0.617021 (-1385 910);
PAINT ORANGE (-1385 910);
FORCEPROP 2 LASTPIN (-1375 850) $PN 131
J 2
(-1385 860);
DISPLAY 0.617021 (-1385 860);
PAINT ORANGE (-1385 860);
FORCEPROP 2 LASTPIN (-1375 800) $PN 134
J 2
(-1385 810);
DISPLAY 0.617021 (-1385 810);
PAINT ORANGE (-1385 810);
FORCEPROP 2 LASTPIN (-1375 750) $PN 136
J 2
(-1385 760);
DISPLAY 0.617021 (-1385 760);
PAINT ORANGE (-1385 760);
FORCEPROP 2 LASTPIN (-1375 700) $PN 138
J 2
(-1385 710);
DISPLAY 0.617021 (-1385 710);
PAINT ORANGE (-1385 710);
FORCEPROP 2 LASTPIN (-375 3000) $PN 147
J 0
(-365 3010);
DISPLAY 0.617021 (-365 3010);
PAINT ORANGE (-365 3010);
FORCEPROP 2 LASTPIN (-375 2900) $PN 151
J 0
(-365 2910);
DISPLAY 0.617021 (-365 2910);
PAINT ORANGE (-365 2910);
FORCEPROP 2 LASTPIN (-375 2850) $PN 154
J 0
(-365 2860);
DISPLAY 0.617021 (-365 2860);
PAINT ORANGE (-365 2860);
FORCEPROP 2 LASTPIN (-375 2800) $PN 156
J 0
(-365 2810);
DISPLAY 0.617021 (-365 2810);
PAINT ORANGE (-365 2810);
FORCEPROP 2 LASTPIN (-375 2750) $PN 158
J 0
(-365 2760);
DISPLAY 0.617021 (-365 2760);
PAINT ORANGE (-365 2760);
FORCEPROP 2 LASTPIN (-375 2700) $PN 160
J 0
(-365 2710);
DISPLAY 0.617021 (-365 2710);
PAINT ORANGE (-365 2710);
FORCEPROP 2 LASTPIN (-375 2650) $PN 162
J 0
(-365 2660);
DISPLAY 0.617021 (-365 2660);
PAINT ORANGE (-365 2660);
FORCEPROP 2 LASTPIN (-375 2600) $PN 165
J 0
(-365 2610);
DISPLAY 0.617021 (-365 2610);
PAINT ORANGE (-365 2610);
FORCEPROP 2 LASTPIN (-375 2550) $PN 167
J 0
(-365 2560);
DISPLAY 0.617021 (-365 2560);
PAINT ORANGE (-365 2560);
FORCEPROP 2 LASTPIN (-375 2500) $PN 169
J 0
(-365 2510);
DISPLAY 0.617021 (-365 2510);
PAINT ORANGE (-365 2510);
FORCEPROP 2 LASTPIN (-375 2400) $PN 173
J 0
(-365 2410);
DISPLAY 0.617021 (-365 2410);
PAINT ORANGE (-365 2410);
FORCEPROP 2 LASTPIN (-375 2350) $PN 176
J 0
(-365 2360);
DISPLAY 0.617021 (-365 2360);
PAINT ORANGE (-365 2360);
FORCEPROP 2 LASTPIN (-375 2300) $PN 178
J 0
(-365 2310);
DISPLAY 0.617021 (-365 2310);
PAINT ORANGE (-365 2310);
FORCEPROP 2 LASTPIN (-375 2200) $PN 182
J 0
(-365 2210);
DISPLAY 0.617021 (-365 2210);
PAINT ORANGE (-365 2210);
FORCEPROP 2 LASTPIN (-375 2150) $PN 184
J 0
(-365 2160);
DISPLAY 0.617021 (-365 2160);
PAINT ORANGE (-365 2160);
FORCEPROP 2 LASTPIN (-375 2100) $PN 187
J 0
(-365 2110);
DISPLAY 0.617021 (-365 2110);
PAINT ORANGE (-365 2110);
FORCEPROP 2 LASTPIN (-375 2050) $PN 189
J 0
(-365 2060);
DISPLAY 0.617021 (-365 2060);
PAINT ORANGE (-365 2060);
FORCEPROP 2 LASTPIN (-375 1950) $PN 193
J 0
(-365 1960);
DISPLAY 0.617021 (-365 1960);
PAINT ORANGE (-365 1960);
FORCEPROP 2 LASTPIN (-375 1900) $PN 195
J 0
(-365 1910);
DISPLAY 0.617021 (-365 1910);
PAINT ORANGE (-365 1910);
FORCEPROP 2 LASTPIN (-375 1850) $PN 198
J 0
(-365 1860);
DISPLAY 0.617021 (-365 1860);
PAINT ORANGE (-365 1860);
FORCEPROP 2 LASTPIN (-375 1800) $PN 200
J 0
(-365 1810);
DISPLAY 0.617021 (-365 1810);
PAINT ORANGE (-365 1810);
FORCEPROP 2 LASTPIN (-375 1750) $PN 202
J 0
(-365 1760);
DISPLAY 0.617021 (-365 1760);
PAINT ORANGE (-365 1760);
FORCEPROP 2 LASTPIN (-375 1700) $PN 239
J 0
(-365 1710);
DISPLAY 0.617021 (-365 1710);
PAINT ORANGE (-365 1710);
FORCEPROP 2 LASTPIN (-375 1650) $PN 241
J 0
(-365 1660);
DISPLAY 0.617021 (-365 1660);
PAINT ORANGE (-365 1660);
FORCEPROP 2 LASTPIN (-375 1600) $PN 243
J 0
(-365 1610);
DISPLAY 0.617021 (-365 1610);
PAINT ORANGE (-365 1610);
FORCEPROP 2 LASTPIN (-375 1550) $PN 246
J 0
(-365 1560);
DISPLAY 0.617021 (-365 1560);
PAINT ORANGE (-365 1560);
FORCEPROP 2 LASTPIN (-375 1500) $PN 248
J 0
(-365 1510);
DISPLAY 0.617021 (-365 1510);
PAINT ORANGE (-365 1510);
FORCEPROP 2 LASTPIN (-375 1450) $PN 250
J 0
(-365 1460);
DISPLAY 0.617021 (-365 1460);
PAINT ORANGE (-365 1460);
FORCEPROP 2 LASTPIN (-375 1400) $PN 252
J 0
(-365 1410);
DISPLAY 0.617021 (-365 1410);
PAINT ORANGE (-365 1410);
FORCEPROP 2 LASTPIN (-375 1350) $PN 254
J 0
(-365 1360);
DISPLAY 0.617021 (-365 1360);
PAINT ORANGE (-365 1360);
FORCEPROP 2 LASTPIN (-375 1300) $PN 257
J 0
(-365 1310);
DISPLAY 0.617021 (-365 1310);
PAINT ORANGE (-365 1310);
FORCEPROP 2 LASTPIN (-375 1250) $PN 259
J 0
(-365 1260);
DISPLAY 0.617021 (-365 1260);
PAINT ORANGE (-365 1260);
FORCEPROP 2 LASTPIN (-375 1200) $PN 261
J 0
(-365 1210);
DISPLAY 0.617021 (-365 1210);
PAINT ORANGE (-365 1210);
FORCEPROP 2 LASTPIN (-375 1150) $PN 263
J 0
(-365 1160);
DISPLAY 0.617021 (-365 1160);
PAINT ORANGE (-365 1160);
FORCEPROP 2 LASTPIN (-375 1100) $PN 265
J 0
(-365 1110);
DISPLAY 0.617021 (-365 1110);
PAINT ORANGE (-365 1110);
FORCEPROP 2 LASTPIN (-375 1050) $PN 268
J 0
(-365 1060);
DISPLAY 0.617021 (-365 1060);
PAINT ORANGE (-365 1060);
FORCEPROP 2 LASTPIN (-375 1000) $PN 270
J 0
(-365 1010);
DISPLAY 0.617021 (-365 1010);
PAINT ORANGE (-365 1010);
FORCEPROP 2 LASTPIN (-375 950) $PN 272
J 0
(-365 960);
DISPLAY 0.617021 (-365 960);
PAINT ORANGE (-365 960);
FORCEPROP 2 LASTPIN (-375 900) $PN 274
J 0
(-365 910);
DISPLAY 0.617021 (-365 910);
PAINT ORANGE (-365 910);
FORCEPROP 2 LASTPIN (-375 850) $PN 276
J 0
(-365 860);
DISPLAY 0.617021 (-365 860);
PAINT ORANGE (-365 860);
FORCEPROP 2 LASTPIN (-375 800) $PN 279
J 0
(-365 810);
DISPLAY 0.617021 (-365 810);
PAINT ORANGE (-365 810);
FORCEPROP 2 LASTPIN (-375 750) $PN 281
J 0
(-365 760);
DISPLAY 0.617021 (-365 760);
PAINT ORANGE (-365 760);
FORCEPROP 2 LASTPIN (-375 700) $PN 283
J 0
(-365 710);
DISPLAY 0.617021 (-365 710);
PAINT ORANGE (-365 710);
FORCEPROP 2 LASTPIN (-375 2000) $PN 191
J 0
(-365 2010);
DISPLAY 0.617021 (-365 2010);
PAINT ORANGE (-365 2010);
FORCEPROP 2 LASTPIN (-1375 2800) $PN 11
J 2
(-1385 2810);
DISPLAY 0.617021 (-1385 2810);
PAINT ORANGE (-1385 2810);
FORCEPROP 2 LASTPIN (-375 2450) $PN 171
J 0
(-365 2460);
DISPLAY 0.617021 (-365 2460);
PAINT ORANGE (-365 2460);
FORCEPROP 2 LASTPIN (-375 2950) $PN 149
J 0
(-365 2960);
DISPLAY 0.617021 (-365 2960);
PAINT ORANGE (-365 2960);
FORCEPROP 2 LASTPIN (-1375 1450) $PN 105
J 2
(-1385 1460);
DISPLAY 0.617021 (-1385 1460);
PAINT ORANGE (-1385 1460);
FORCEPROP 2 LASTPIN (-375 2250) $PN 180
J 0
(-365 2260);
DISPLAY 0.617021 (-365 2260);
PAINT ORANGE (-365 2260);
FORCEPROP 2 LASTPIN (-1375 2300) $PN 33
J 2
(-1385 2310);
DISPLAY 0.617021 (-1385 2310);
PAINT ORANGE (-1385 2310);
FORCEPROP 0 LAST BOM_SS NOPOP
J 0
(-1153 3211);
DISPLAY 1.021277 (-1153 3211);
PAINT BROWN (-1153 3211);
DISPLAY BOTH (-1153 3211);
FORCEPROP 2 LASTPIN (-1375 1500) $PN 103
J 2
(-1385 1510);
DISPLAY 0.617021 (-1385 1510);
PAINT ORANGE (-1385 1510);
FORCEPROP 1 LAST PACK_TYPE PIP
J 0
(-1325 3300);
PAINT SKYBLUE (-1325 3300);
DISPLAY INVISIBLE (-1325 3300);
FORCEPROP 2 LAST BOM_COST MEM
J 0
(-875 1850);
PAINT ORANGE (-875 1850);
DISPLAY INVISIBLE (-875 1850);
FORCEPROP 2 LAST CDS_LIB mstr_sconn
J 0
(-875 1850);
PAINT ORANGE (-875 1850);
DISPLAY INVISIBLE (-875 1850);
FORCEPROP 2 LAST SEC_TYPE PIP
J 0
(-1325 3300);
DISPLAY 1.021277 (-1325 3300);
PAINT ORANGE (-1325 3300);
DISPLAY INVISIBLE (-1325 3300);
FORCEPROP 2 LAST SEC 3
J 0
(-1325 3300);
DISPLAY 0.680851 (-1325 3300);
PAINT MONO (-1325 3300);
DISPLAY INVISIBLE (-1325 3300);
FORCEPROP 2 LAST CDS_LOCATION J9U1
J 0
(-1325 3250);
DISPLAY 0.617021 (-1325 3250);
PAINT AQUA (-1325 3250);
DISPLAY INVISIBLE (-1325 3250);
FORCEPROP 1 LAST PATH I138
J 0
(-875 3200);
PAINT GREEN (-875 3200);
DISPLAY INVISIBLE (-875 3200);
FORCEPROP 2 LAST ROOM DDR4_GH_H
J 0
(-875 1850);
PAINT ORANGE (-875 1850);
DISPLAY INVISIBLE (-875 1850);
FORCEADD OFFPAGE..1
(-6625 2300);
FORCEPROP 2 LAST $XR1 79 
J 0
(-6966 2300);
DISPLAY 0.638298 (-6966 2300);
PAINT MONO (-6966 2300);
FORCEPROP 2 LAST $XR0 58 
J 0
(-6876 2300);
DISPLAY 0.638298 (-6876 2300);
PAINT MONO (-6876 2300);
FORCEPROP 2 LAST CDS_LIB mstr_standard
J 0
(-6625 2300);
DISPLAY 0.787234 (-6625 2300);
PAINT MONO (-6625 2300);
DISPLAY INVISIBLE (-6625 2300);
FORCEPROP 1 LAST OFFPAGE TRUE
J 0
(-6300 2175);
DISPLAY 0.936170 (-6300 2175);
PAINT GREEN (-6300 2175);
DISPLAY INVISIBLE (-6300 2175);
FORCEPROP 1 LAST COMMENT_BODY TRUE
J 0
(-6500 2200);
DISPLAY 0.936170 (-6500 2200);
PAINT GREEN (-6500 2200);
DISPLAY INVISIBLE (-6500 2200);
FORCEPROP 2 LAST PATH I14
J 0
(-6875 2350);
DISPLAY 1.021277 (-6875 2350);
PAINT ORANGE (-6875 2350);
DISPLAY INVISIBLE (-6875 2350);
FORCEADD TAP..6
R 2
(-1975 3000);
FORCEPROP 3 LASTPIN (-2025 3000) SIG_NAME M_H_DQS_DP<1>
J 0
(-2015 3010);
DISPLAY 0.659574 (-2015 3010);
PAINT MONO (-2015 3010);
DISPLAY INVISIBLE (-2015 3010);
FORCEPROP 1 LASTPIN (-2025 3000) BN 1
J 2
(-1975 3010);
DISPLAY 0.617021 (-1975 3010);
PAINT PINK (-1975 3010);
FORCEPROP 2 LAST CDS_LIB mstr_standard
J 0
(-1975 3000);
DISPLAY 0.787234 (-1975 3000);
PAINT MONO (-1975 3000);
DISPLAY INVISIBLE (-1975 3000);
FORCEPROP 1 LAST BODY_TYPE PLUMBING
J 2
(-1975 2950);
DISPLAY 1.234043 (-1975 2950);
PAINT GREEN (-1975 2950);
DISPLAY INVISIBLE (-1975 2950);
FORCEPROP 1 LAST HDL_TAP TRUE
J 2
(-2300 2875);
DISPLAY 1.234043 (-2300 2875);
PAINT GREEN (-2300 2875);
DISPLAY INVISIBLE (-2300 2875);
FORCEPROP 1 LAST PATH I142
J 2
(-1973 3000);
DISPLAY 0.872340 (-1973 3000);
PAINT GREEN (-1973 3000);
DISPLAY INVISIBLE (-1973 3000);
FORCEADD TAP..6
R 2
(-1975 2900);
FORCEPROP 3 LASTPIN (-2025 2900) SIG_NAME M_H_DQS_DP<0>
J 0
(-2015 2910);
DISPLAY 0.659574 (-2015 2910);
PAINT MONO (-2015 2910);
DISPLAY INVISIBLE (-2015 2910);
FORCEPROP 1 LASTPIN (-2025 2900) BN 0
J 2
(-1975 2910);
DISPLAY 0.617021 (-1975 2910);
PAINT PINK (-1975 2910);
FORCEPROP 2 LAST CDS_LIB mstr_standard
J 0
(-1975 2900);
DISPLAY 0.787234 (-1975 2900);
PAINT MONO (-1975 2900);
DISPLAY INVISIBLE (-1975 2900);
FORCEPROP 1 LAST BODY_TYPE PLUMBING
J 2
(-1975 2850);
DISPLAY 1.234043 (-1975 2850);
PAINT GREEN (-1975 2850);
DISPLAY INVISIBLE (-1975 2850);
FORCEPROP 1 LAST HDL_TAP TRUE
J 2
(-2300 2775);
DISPLAY 1.234043 (-2300 2775);
PAINT GREEN (-2300 2775);
DISPLAY INVISIBLE (-2300 2775);
FORCEPROP 1 LAST PATH I143
J 2
(-1973 2900);
DISPLAY 0.872340 (-1973 2900);
PAINT GREEN (-1973 2900);
DISPLAY INVISIBLE (-1973 2900);
FORCEADD TAP..6
R 2
(-1775 2850);
FORCEPROP 3 LASTPIN (-1825 2850) SIG_NAME M_H_DQS_DN<0>
J 0
(-1815 2860);
DISPLAY 0.659574 (-1815 2860);
PAINT MONO (-1815 2860);
DISPLAY INVISIBLE (-1815 2860);
FORCEPROP 1 LASTPIN (-1825 2850) BN 0
J 2
(-1775 2860);
DISPLAY 0.617021 (-1775 2860);
PAINT PINK (-1775 2860);
FORCEPROP 2 LAST CDS_LIB mstr_standard
J 0
(-1775 2850);
DISPLAY 0.787234 (-1775 2850);
PAINT MONO (-1775 2850);
DISPLAY INVISIBLE (-1775 2850);
FORCEPROP 1 LAST BODY_TYPE PLUMBING
J 2
(-1775 2800);
DISPLAY 1.234043 (-1775 2800);
PAINT GREEN (-1775 2800);
DISPLAY INVISIBLE (-1775 2800);
FORCEPROP 1 LAST HDL_TAP TRUE
J 2
(-2100 2725);
DISPLAY 1.234043 (-2100 2725);
PAINT GREEN (-2100 2725);
DISPLAY INVISIBLE (-2100 2725);
FORCEPROP 1 LAST PATH I144
J 2
(-1773 2850);
DISPLAY 0.872340 (-1773 2850);
PAINT GREEN (-1773 2850);
DISPLAY INVISIBLE (-1773 2850);
FORCEADD TAP..6
R 2
(-1775 2950);
FORCEPROP 3 LASTPIN (-1825 2950) SIG_NAME M_H_DQS_DN<1>
J 0
(-1815 2960);
DISPLAY 0.659574 (-1815 2960);
PAINT MONO (-1815 2960);
DISPLAY INVISIBLE (-1815 2960);
FORCEPROP 1 LASTPIN (-1825 2950) BN 1
J 2
(-1775 2960);
DISPLAY 0.617021 (-1775 2960);
PAINT PINK (-1775 2960);
FORCEPROP 2 LAST CDS_LIB mstr_standard
J 0
(-1775 2950);
DISPLAY 0.787234 (-1775 2950);
PAINT MONO (-1775 2950);
DISPLAY INVISIBLE (-1775 2950);
FORCEPROP 1 LAST BODY_TYPE PLUMBING
J 2
(-1775 2900);
DISPLAY 1.234043 (-1775 2900);
PAINT GREEN (-1775 2900);
DISPLAY INVISIBLE (-1775 2900);
FORCEPROP 1 LAST HDL_TAP TRUE
J 2
(-2100 2825);
DISPLAY 1.234043 (-2100 2825);
PAINT GREEN (-2100 2825);
DISPLAY INVISIBLE (-2100 2825);
FORCEPROP 1 LAST PATH I145
J 2
(-1773 2950);
DISPLAY 0.872340 (-1773 2950);
PAINT GREEN (-1773 2950);
DISPLAY INVISIBLE (-1773 2950);
FORCEADD TAP..6
R 2
(-1975 3100);
FORCEPROP 3 LASTPIN (-2025 3100) SIG_NAME M_H_DQS_DP<2>
J 0
(-2015 3110);
DISPLAY 0.659574 (-2015 3110);
PAINT MONO (-2015 3110);
DISPLAY INVISIBLE (-2015 3110);
FORCEPROP 1 LASTPIN (-2025 3100) BN 2
J 2
(-1975 3110);
DISPLAY 0.617021 (-1975 3110);
PAINT PINK (-1975 3110);
FORCEPROP 2 LAST CDS_LIB mstr_standard
J 0
(-1975 3100);
DISPLAY 0.787234 (-1975 3100);
PAINT MONO (-1975 3100);
DISPLAY INVISIBLE (-1975 3100);
FORCEPROP 1 LAST BODY_TYPE PLUMBING
J 2
(-1975 3050);
DISPLAY 1.234043 (-1975 3050);
PAINT GREEN (-1975 3050);
DISPLAY INVISIBLE (-1975 3050);
FORCEPROP 1 LAST HDL_TAP TRUE
J 2
(-2300 2975);
DISPLAY 1.234043 (-2300 2975);
PAINT GREEN (-2300 2975);
DISPLAY INVISIBLE (-2300 2975);
FORCEPROP 1 LAST PATH I146
J 2
(-1973 3100);
DISPLAY 0.872340 (-1973 3100);
PAINT GREEN (-1973 3100);
DISPLAY INVISIBLE (-1973 3100);
FORCEADD TAP..6
R 2
(-1975 3200);
FORCEPROP 3 LASTPIN (-2025 3200) SIG_NAME M_H_DQS_DP<3>
J 0
(-2015 3210);
DISPLAY 0.659574 (-2015 3210);
PAINT MONO (-2015 3210);
DISPLAY INVISIBLE (-2015 3210);
FORCEPROP 1 LASTPIN (-2025 3200) BN 3
J 2
(-1975 3210);
DISPLAY 0.617021 (-1975 3210);
PAINT PINK (-1975 3210);
FORCEPROP 2 LAST CDS_LIB mstr_standard
J 0
(-1975 3200);
DISPLAY 0.787234 (-1975 3200);
PAINT MONO (-1975 3200);
DISPLAY INVISIBLE (-1975 3200);
FORCEPROP 1 LAST BODY_TYPE PLUMBING
J 2
(-1975 3150);
DISPLAY 1.234043 (-1975 3150);
PAINT GREEN (-1975 3150);
DISPLAY INVISIBLE (-1975 3150);
FORCEPROP 1 LAST HDL_TAP TRUE
J 2
(-2300 3075);
DISPLAY 1.234043 (-2300 3075);
PAINT GREEN (-2300 3075);
DISPLAY INVISIBLE (-2300 3075);
FORCEPROP 1 LAST PATH I147
J 2
(-1973 3200);
DISPLAY 0.872340 (-1973 3200);
PAINT GREEN (-1973 3200);
DISPLAY INVISIBLE (-1973 3200);
FORCEADD TAP..6
R 2
(-1975 3500);
FORCEPROP 3 LASTPIN (-2025 3500) SIG_NAME M_H_DQS_DP<6>
J 0
(-2015 3510);
DISPLAY 0.659574 (-2015 3510);
PAINT MONO (-2015 3510);
DISPLAY INVISIBLE (-2015 3510);
FORCEPROP 1 LASTPIN (-2025 3500) BN 6
J 2
(-1975 3510);
DISPLAY 0.617021 (-1975 3510);
PAINT PINK (-1975 3510);
FORCEPROP 2 LAST CDS_LIB mstr_standard
J 0
(-1975 3500);
DISPLAY 0.787234 (-1975 3500);
PAINT MONO (-1975 3500);
DISPLAY INVISIBLE (-1975 3500);
FORCEPROP 1 LAST BODY_TYPE PLUMBING
J 2
(-1975 3450);
DISPLAY 1.234043 (-1975 3450);
PAINT GREEN (-1975 3450);
DISPLAY INVISIBLE (-1975 3450);
FORCEPROP 1 LAST HDL_TAP TRUE
J 2
(-2300 3375);
DISPLAY 1.234043 (-2300 3375);
PAINT GREEN (-2300 3375);
DISPLAY INVISIBLE (-2300 3375);
FORCEPROP 1 LAST PATH I148
J 2
(-1973 3500);
DISPLAY 0.872340 (-1973 3500);
PAINT GREEN (-1973 3500);
DISPLAY INVISIBLE (-1973 3500);
FORCEADD TAP..6
R 2
(-1975 3400);
FORCEPROP 3 LASTPIN (-2025 3400) SIG_NAME M_H_DQS_DP<5>
J 0
(-2015 3410);
DISPLAY 0.659574 (-2015 3410);
PAINT MONO (-2015 3410);
DISPLAY INVISIBLE (-2015 3410);
FORCEPROP 1 LASTPIN (-2025 3400) BN 5
J 2
(-1975 3410);
DISPLAY 0.617021 (-1975 3410);
PAINT PINK (-1975 3410);
FORCEPROP 2 LAST CDS_LIB mstr_standard
J 0
(-1975 3400);
DISPLAY 0.787234 (-1975 3400);
PAINT MONO (-1975 3400);
DISPLAY INVISIBLE (-1975 3400);
FORCEPROP 1 LAST BODY_TYPE PLUMBING
J 2
(-1975 3350);
DISPLAY 1.234043 (-1975 3350);
PAINT GREEN (-1975 3350);
DISPLAY INVISIBLE (-1975 3350);
FORCEPROP 1 LAST HDL_TAP TRUE
J 2
(-2300 3275);
DISPLAY 1.234043 (-2300 3275);
PAINT GREEN (-2300 3275);
DISPLAY INVISIBLE (-2300 3275);
FORCEPROP 1 LAST PATH I149
J 2
(-1973 3400);
DISPLAY 0.872340 (-1973 3400);
PAINT GREEN (-1973 3400);
DISPLAY INVISIBLE (-1973 3400);
FORCEADD OFFPAGE..1
(-6625 2500);
FORCEPROP 2 LAST $XR1 79 
J 0
(-6936 2500);
DISPLAY 0.638298 (-6936 2500);
PAINT MONO (-6936 2500);
FORCEPROP 2 LAST $XR0 58 
J 0
(-6846 2500);
DISPLAY 0.638298 (-6846 2500);
PAINT MONO (-6846 2500);
FORCEPROP 2 LAST CDS_LIB mstr_standard
J 0
(-6625 2500);
DISPLAY 0.787234 (-6625 2500);
PAINT MONO (-6625 2500);
DISPLAY INVISIBLE (-6625 2500);
FORCEPROP 1 LAST OFFPAGE TRUE
J 0
(-6300 2375);
DISPLAY 0.936170 (-6300 2375);
PAINT GREEN (-6300 2375);
DISPLAY INVISIBLE (-6300 2375);
FORCEPROP 1 LAST COMMENT_BODY TRUE
J 0
(-6500 2400);
DISPLAY 0.936170 (-6500 2400);
PAINT GREEN (-6500 2400);
DISPLAY INVISIBLE (-6500 2400);
FORCEPROP 2 LAST PATH I15
J 0
(-6875 2550);
DISPLAY 1.021277 (-6875 2550);
PAINT ORANGE (-6875 2550);
DISPLAY INVISIBLE (-6875 2550);
FORCEADD TAP..6
R 2
(-1975 3300);
FORCEPROP 3 LASTPIN (-2025 3300) SIG_NAME M_H_DQS_DP<4>
J 0
(-2015 3310);
DISPLAY 0.659574 (-2015 3310);
PAINT MONO (-2015 3310);
DISPLAY INVISIBLE (-2015 3310);
FORCEPROP 1 LASTPIN (-2025 3300) BN 4
J 2
(-1975 3310);
DISPLAY 0.617021 (-1975 3310);
PAINT PINK (-1975 3310);
FORCEPROP 2 LAST CDS_LIB mstr_standard
J 0
(-1975 3300);
DISPLAY 0.787234 (-1975 3300);
PAINT MONO (-1975 3300);
DISPLAY INVISIBLE (-1975 3300);
FORCEPROP 1 LAST BODY_TYPE PLUMBING
J 2
(-1975 3250);
DISPLAY 1.234043 (-1975 3250);
PAINT GREEN (-1975 3250);
DISPLAY INVISIBLE (-1975 3250);
FORCEPROP 1 LAST HDL_TAP TRUE
J 2
(-2300 3175);
DISPLAY 1.234043 (-2300 3175);
PAINT GREEN (-2300 3175);
DISPLAY INVISIBLE (-2300 3175);
FORCEPROP 1 LAST PATH I150
J 2
(-1973 3300);
DISPLAY 0.872340 (-1973 3300);
PAINT GREEN (-1973 3300);
DISPLAY INVISIBLE (-1973 3300);
FORCEADD TAP..6
R 2
(-1775 3150);
FORCEPROP 3 LASTPIN (-1825 3150) SIG_NAME M_H_DQS_DN<3>
J 0
(-1815 3160);
DISPLAY 0.659574 (-1815 3160);
PAINT MONO (-1815 3160);
DISPLAY INVISIBLE (-1815 3160);
FORCEPROP 1 LASTPIN (-1825 3150) BN 3
J 2
(-1775 3160);
DISPLAY 0.617021 (-1775 3160);
PAINT PINK (-1775 3160);
FORCEPROP 2 LAST CDS_LIB mstr_standard
J 0
(-1775 3150);
DISPLAY 0.787234 (-1775 3150);
PAINT MONO (-1775 3150);
DISPLAY INVISIBLE (-1775 3150);
FORCEPROP 1 LAST BODY_TYPE PLUMBING
J 2
(-1775 3100);
DISPLAY 1.234043 (-1775 3100);
PAINT GREEN (-1775 3100);
DISPLAY INVISIBLE (-1775 3100);
FORCEPROP 1 LAST HDL_TAP TRUE
J 2
(-2100 3025);
DISPLAY 1.234043 (-2100 3025);
PAINT GREEN (-2100 3025);
DISPLAY INVISIBLE (-2100 3025);
FORCEPROP 1 LAST PATH I151
J 2
(-1773 3150);
DISPLAY 0.872340 (-1773 3150);
PAINT GREEN (-1773 3150);
DISPLAY INVISIBLE (-1773 3150);
FORCEADD TAP..6
R 2
(-1775 3050);
FORCEPROP 3 LASTPIN (-1825 3050) SIG_NAME M_H_DQS_DN<2>
J 0
(-1815 3060);
DISPLAY 0.659574 (-1815 3060);
PAINT MONO (-1815 3060);
DISPLAY INVISIBLE (-1815 3060);
FORCEPROP 1 LASTPIN (-1825 3050) BN 2
J 2
(-1775 3060);
DISPLAY 0.617021 (-1775 3060);
PAINT PINK (-1775 3060);
FORCEPROP 2 LAST CDS_LIB mstr_standard
J 0
(-1775 3050);
DISPLAY 0.787234 (-1775 3050);
PAINT MONO (-1775 3050);
DISPLAY INVISIBLE (-1775 3050);
FORCEPROP 1 LAST BODY_TYPE PLUMBING
J 2
(-1775 3000);
DISPLAY 1.234043 (-1775 3000);
PAINT GREEN (-1775 3000);
DISPLAY INVISIBLE (-1775 3000);
FORCEPROP 1 LAST HDL_TAP TRUE
J 2
(-2100 2925);
DISPLAY 1.234043 (-2100 2925);
PAINT GREEN (-2100 2925);
DISPLAY INVISIBLE (-2100 2925);
FORCEPROP 1 LAST PATH I152
J 2
(-1773 3050);
DISPLAY 0.872340 (-1773 3050);
PAINT GREEN (-1773 3050);
DISPLAY INVISIBLE (-1773 3050);
FORCEADD TAP..6
R 2
(-1775 3250);
FORCEPROP 3 LASTPIN (-1825 3250) SIG_NAME M_H_DQS_DN<4>
J 0
(-1815 3260);
DISPLAY 0.659574 (-1815 3260);
PAINT MONO (-1815 3260);
DISPLAY INVISIBLE (-1815 3260);
FORCEPROP 1 LASTPIN (-1825 3250) BN 4
J 2
(-1775 3260);
DISPLAY 0.617021 (-1775 3260);
PAINT PINK (-1775 3260);
FORCEPROP 2 LAST CDS_LIB mstr_standard
J 0
(-1775 3250);
DISPLAY 0.787234 (-1775 3250);
PAINT MONO (-1775 3250);
DISPLAY INVISIBLE (-1775 3250);
FORCEPROP 1 LAST BODY_TYPE PLUMBING
J 2
(-1775 3200);
DISPLAY 1.234043 (-1775 3200);
PAINT GREEN (-1775 3200);
DISPLAY INVISIBLE (-1775 3200);
FORCEPROP 1 LAST HDL_TAP TRUE
J 2
(-2100 3125);
DISPLAY 1.234043 (-2100 3125);
PAINT GREEN (-2100 3125);
DISPLAY INVISIBLE (-2100 3125);
FORCEPROP 1 LAST PATH I153
J 2
(-1773 3250);
DISPLAY 0.872340 (-1773 3250);
PAINT GREEN (-1773 3250);
DISPLAY INVISIBLE (-1773 3250);
FORCEADD TAP..6
R 2
(-1775 3350);
FORCEPROP 3 LASTPIN (-1825 3350) SIG_NAME M_H_DQS_DN<5>
J 0
(-1815 3360);
DISPLAY 0.659574 (-1815 3360);
PAINT MONO (-1815 3360);
DISPLAY INVISIBLE (-1815 3360);
FORCEPROP 1 LASTPIN (-1825 3350) BN 5
J 2
(-1775 3360);
DISPLAY 0.617021 (-1775 3360);
PAINT PINK (-1775 3360);
FORCEPROP 2 LAST CDS_LIB mstr_standard
J 0
(-1775 3350);
DISPLAY 0.787234 (-1775 3350);
PAINT MONO (-1775 3350);
DISPLAY INVISIBLE (-1775 3350);
FORCEPROP 1 LAST BODY_TYPE PLUMBING
J 2
(-1775 3300);
DISPLAY 1.234043 (-1775 3300);
PAINT GREEN (-1775 3300);
DISPLAY INVISIBLE (-1775 3300);
FORCEPROP 1 LAST HDL_TAP TRUE
J 2
(-2100 3225);
DISPLAY 1.234043 (-2100 3225);
PAINT GREEN (-2100 3225);
DISPLAY INVISIBLE (-2100 3225);
FORCEPROP 1 LAST PATH I154
J 2
(-1773 3350);
DISPLAY 0.872340 (-1773 3350);
PAINT GREEN (-1773 3350);
DISPLAY INVISIBLE (-1773 3350);
FORCEADD TAP..6
R 2
(-1775 3450);
FORCEPROP 3 LASTPIN (-1825 3450) SIG_NAME M_H_DQS_DN<6>
J 0
(-1815 3460);
DISPLAY 0.659574 (-1815 3460);
PAINT MONO (-1815 3460);
DISPLAY INVISIBLE (-1815 3460);
FORCEPROP 1 LASTPIN (-1825 3450) BN 6
J 2
(-1775 3460);
DISPLAY 0.617021 (-1775 3460);
PAINT PINK (-1775 3460);
FORCEPROP 2 LAST CDS_LIB mstr_standard
J 0
(-1775 3450);
DISPLAY 0.787234 (-1775 3450);
PAINT MONO (-1775 3450);
DISPLAY INVISIBLE (-1775 3450);
FORCEPROP 1 LAST BODY_TYPE PLUMBING
J 2
(-1775 3400);
DISPLAY 1.234043 (-1775 3400);
PAINT GREEN (-1775 3400);
DISPLAY INVISIBLE (-1775 3400);
FORCEPROP 1 LAST HDL_TAP TRUE
J 2
(-2100 3325);
DISPLAY 1.234043 (-2100 3325);
PAINT GREEN (-2100 3325);
DISPLAY INVISIBLE (-2100 3325);
FORCEPROP 1 LAST PATH I155
J 2
(-1773 3450);
DISPLAY 0.872340 (-1773 3450);
PAINT GREEN (-1773 3450);
DISPLAY INVISIBLE (-1773 3450);
FORCEADD GND..1
R 2
(-175 550);
FORCEPROP 3 LASTPIN (-175 600) SIG_NAME GND\g
J 0
(-165 610);
DISPLAY 0.659574 (-165 610);
PAINT MONO (-165 610);
DISPLAY INVISIBLE (-165 610);
FORCEPROP 1 LAST VOLTAGE 0
J 0
(-175 550);
PAINT SKYBLUE (-175 550);
DISPLAY INVISIBLE (-175 550);
FORCEPROP 2 LAST CDS_LIB mstr_symbols
J 0
(-175 550);
DISPLAY 0.787234 (-175 550);
PAINT MONO (-175 550);
DISPLAY INVISIBLE (-175 550);
FORCEPROP 1 LAST SIZE 1B
J 2
(-250 500);
DISPLAY 1.170213 (-250 500);
PAINT GREEN (-250 500);
DISPLAY INVISIBLE (-250 500);
FORCEPROP 2 LAST BOM_COST MEM
J 0
(-175 555);
PAINT ORANGE (-175 555);
DISPLAY INVISIBLE (-175 555);
FORCEPROP 1 LAST BODY_TYPE PLUMBING
J 2
(-130 507);
DISPLAY 0.340426 (-130 507);
PAINT GREEN (-130 507);
DISPLAY INVISIBLE (-130 507);
FORCEPROP 1 LAST PATH I156
J 2
(-250 550);
DISPLAY 0.872340 (-250 550);
PAINT AQUA (-250 550);
DISPLAY INVISIBLE (-250 550);
FORCEPROP 2 LAST ROOM DDR4_GH_G
J 0
(-175 555);
PAINT ORANGE (-175 555);
DISPLAY INVISIBLE (-175 555);
FORCEPROP 1 LAST HDL_POWER GND
J 2
(-175 700);
DISPLAY 0.553191 (-175 700);
PAINT GREEN (-175 700);
DISPLAY INVISIBLE (-175 700);
FORCEADD TAP..6
R 2
(-1975 3800);
FORCEPROP 3 LASTPIN (-2025 3800) SIG_NAME M_H_DQS_DP<9>
J 0
(-2015 3810);
DISPLAY 0.659574 (-2015 3810);
PAINT MONO (-2015 3810);
DISPLAY INVISIBLE (-2015 3810);
FORCEPROP 1 LASTPIN (-2025 3800) BN 9
J 2
(-1975 3810);
DISPLAY 0.617021 (-1975 3810);
PAINT PINK (-1975 3810);
FORCEPROP 2 LAST CDS_LIB mstr_standard
J 0
(-1975 3800);
DISPLAY 0.787234 (-1975 3800);
PAINT MONO (-1975 3800);
DISPLAY INVISIBLE (-1975 3800);
FORCEPROP 1 LAST BODY_TYPE PLUMBING
J 2
(-1975 3750);
DISPLAY 1.234043 (-1975 3750);
PAINT GREEN (-1975 3750);
DISPLAY INVISIBLE (-1975 3750);
FORCEPROP 1 LAST HDL_TAP TRUE
J 2
(-2300 3675);
DISPLAY 1.234043 (-2300 3675);
PAINT GREEN (-2300 3675);
DISPLAY INVISIBLE (-2300 3675);
FORCEPROP 1 LAST PATH I157
J 2
(-1973 3800);
DISPLAY 0.872340 (-1973 3800);
PAINT GREEN (-1973 3800);
DISPLAY INVISIBLE (-1973 3800);
FORCEADD TAP..6
R 2
(-1975 3600);
FORCEPROP 3 LASTPIN (-2025 3600) SIG_NAME M_H_DQS_DP<7>
J 0
(-2015 3610);
DISPLAY 0.659574 (-2015 3610);
PAINT MONO (-2015 3610);
DISPLAY INVISIBLE (-2015 3610);
FORCEPROP 1 LASTPIN (-2025 3600) BN 7
J 2
(-1975 3610);
DISPLAY 0.617021 (-1975 3610);
PAINT PINK (-1975 3610);
FORCEPROP 2 LAST CDS_LIB mstr_standard
J 0
(-1975 3600);
DISPLAY 0.787234 (-1975 3600);
PAINT MONO (-1975 3600);
DISPLAY INVISIBLE (-1975 3600);
FORCEPROP 1 LAST BODY_TYPE PLUMBING
J 2
(-1975 3550);
DISPLAY 1.234043 (-1975 3550);
PAINT GREEN (-1975 3550);
DISPLAY INVISIBLE (-1975 3550);
FORCEPROP 1 LAST HDL_TAP TRUE
J 2
(-2300 3475);
DISPLAY 1.234043 (-2300 3475);
PAINT GREEN (-2300 3475);
DISPLAY INVISIBLE (-2300 3475);
FORCEPROP 1 LAST PATH I158
J 2
(-1973 3600);
DISPLAY 0.872340 (-1973 3600);
PAINT GREEN (-1973 3600);
DISPLAY INVISIBLE (-1973 3600);
FORCEADD TAP..6
R 2
(-1975 3700);
FORCEPROP 3 LASTPIN (-2025 3700) SIG_NAME M_H_DQS_DP<8>
J 0
(-2015 3710);
DISPLAY 0.659574 (-2015 3710);
PAINT MONO (-2015 3710);
DISPLAY INVISIBLE (-2015 3710);
FORCEPROP 1 LASTPIN (-2025 3700) BN 8
J 2
(-1975 3710);
DISPLAY 0.617021 (-1975 3710);
PAINT PINK (-1975 3710);
FORCEPROP 2 LAST CDS_LIB mstr_standard
J 0
(-1975 3700);
DISPLAY 0.787234 (-1975 3700);
PAINT MONO (-1975 3700);
DISPLAY INVISIBLE (-1975 3700);
FORCEPROP 1 LAST BODY_TYPE PLUMBING
J 2
(-1975 3650);
DISPLAY 1.234043 (-1975 3650);
PAINT GREEN (-1975 3650);
DISPLAY INVISIBLE (-1975 3650);
FORCEPROP 1 LAST HDL_TAP TRUE
J 2
(-2300 3575);
DISPLAY 1.234043 (-2300 3575);
PAINT GREEN (-2300 3575);
DISPLAY INVISIBLE (-2300 3575);
FORCEPROP 1 LAST PATH I159
J 2
(-1973 3700);
DISPLAY 0.872340 (-1973 3700);
PAINT GREEN (-1973 3700);
DISPLAY INVISIBLE (-1973 3700);
FORCEADD OFFPAGE..1
(-6625 2650);
FORCEPROP 2 LAST $XR1 79 
J 0
(-6936 2650);
DISPLAY 0.638298 (-6936 2650);
PAINT MONO (-6936 2650);
FORCEPROP 2 LAST $XR0 58 
J 0
(-6846 2650);
DISPLAY 0.638298 (-6846 2650);
PAINT MONO (-6846 2650);
FORCEPROP 2 LAST CDS_LIB mstr_standard
J 0
(-6625 2650);
DISPLAY 0.787234 (-6625 2650);
PAINT MONO (-6625 2650);
DISPLAY INVISIBLE (-6625 2650);
FORCEPROP 1 LAST OFFPAGE TRUE
J 0
(-6300 2525);
DISPLAY 0.936170 (-6300 2525);
PAINT GREEN (-6300 2525);
DISPLAY INVISIBLE (-6300 2525);
FORCEPROP 1 LAST COMMENT_BODY TRUE
J 0
(-6500 2550);
DISPLAY 0.936170 (-6500 2550);
PAINT GREEN (-6500 2550);
DISPLAY INVISIBLE (-6500 2550);
FORCEPROP 2 LAST PATH I16
J 0
(-6875 2700);
DISPLAY 1.021277 (-6875 2700);
PAINT ORANGE (-6875 2700);
DISPLAY INVISIBLE (-6875 2700);
FORCEADD TAP..6
R 2
(-1975 4000);
FORCEPROP 3 LASTPIN (-2025 4000) SIG_NAME M_H_DQS_DP<11>
J 0
(-2015 4010);
DISPLAY 0.659574 (-2015 4010);
PAINT MONO (-2015 4010);
DISPLAY INVISIBLE (-2015 4010);
FORCEPROP 1 LASTPIN (-2025 4000) BN 11
J 2
(-1975 4010);
DISPLAY 0.617021 (-1975 4010);
PAINT PINK (-1975 4010);
FORCEPROP 2 LAST CDS_LIB mstr_standard
J 0
(-1975 4000);
DISPLAY 0.787234 (-1975 4000);
PAINT MONO (-1975 4000);
DISPLAY INVISIBLE (-1975 4000);
FORCEPROP 1 LAST BODY_TYPE PLUMBING
J 2
(-1975 3950);
DISPLAY 1.234043 (-1975 3950);
PAINT GREEN (-1975 3950);
DISPLAY INVISIBLE (-1975 3950);
FORCEPROP 1 LAST HDL_TAP TRUE
J 2
(-2300 3875);
DISPLAY 1.234043 (-2300 3875);
PAINT GREEN (-2300 3875);
DISPLAY INVISIBLE (-2300 3875);
FORCEPROP 1 LAST PATH I160
J 2
(-1973 4000);
DISPLAY 0.872340 (-1973 4000);
PAINT GREEN (-1973 4000);
DISPLAY INVISIBLE (-1973 4000);
FORCEADD TAP..6
R 2
(-1975 3900);
FORCEPROP 3 LASTPIN (-2025 3900) SIG_NAME M_H_DQS_DP<10>
J 0
(-2015 3910);
DISPLAY 0.659574 (-2015 3910);
PAINT MONO (-2015 3910);
DISPLAY INVISIBLE (-2015 3910);
FORCEPROP 1 LASTPIN (-2025 3900) BN 10
J 2
(-1975 3910);
DISPLAY 0.617021 (-1975 3910);
PAINT PINK (-1975 3910);
FORCEPROP 2 LAST CDS_LIB mstr_standard
J 0
(-1975 3900);
DISPLAY 0.787234 (-1975 3900);
PAINT MONO (-1975 3900);
DISPLAY INVISIBLE (-1975 3900);
FORCEPROP 1 LAST BODY_TYPE PLUMBING
J 2
(-1975 3850);
DISPLAY 1.234043 (-1975 3850);
PAINT GREEN (-1975 3850);
DISPLAY INVISIBLE (-1975 3850);
FORCEPROP 1 LAST HDL_TAP TRUE
J 2
(-2300 3775);
DISPLAY 1.234043 (-2300 3775);
PAINT GREEN (-2300 3775);
DISPLAY INVISIBLE (-2300 3775);
FORCEPROP 1 LAST PATH I161
J 2
(-1973 3900);
DISPLAY 0.872340 (-1973 3900);
PAINT GREEN (-1973 3900);
DISPLAY INVISIBLE (-1973 3900);
FORCEADD TAP..6
R 2
(-1775 3650);
FORCEPROP 3 LASTPIN (-1825 3650) SIG_NAME M_H_DQS_DN<8>
J 0
(-1815 3660);
DISPLAY 0.659574 (-1815 3660);
PAINT MONO (-1815 3660);
DISPLAY INVISIBLE (-1815 3660);
FORCEPROP 1 LASTPIN (-1825 3650) BN 8
J 2
(-1775 3660);
DISPLAY 0.617021 (-1775 3660);
PAINT PINK (-1775 3660);
FORCEPROP 2 LAST CDS_LIB mstr_standard
J 0
(-1775 3650);
DISPLAY 0.787234 (-1775 3650);
PAINT MONO (-1775 3650);
DISPLAY INVISIBLE (-1775 3650);
FORCEPROP 1 LAST BODY_TYPE PLUMBING
J 2
(-1775 3600);
DISPLAY 1.234043 (-1775 3600);
PAINT GREEN (-1775 3600);
DISPLAY INVISIBLE (-1775 3600);
FORCEPROP 1 LAST HDL_TAP TRUE
J 2
(-2100 3525);
DISPLAY 1.234043 (-2100 3525);
PAINT GREEN (-2100 3525);
DISPLAY INVISIBLE (-2100 3525);
FORCEPROP 1 LAST PATH I162
J 2
(-1773 3650);
DISPLAY 0.872340 (-1773 3650);
PAINT GREEN (-1773 3650);
DISPLAY INVISIBLE (-1773 3650);
FORCEADD TAP..6
R 2
(-1775 3550);
FORCEPROP 3 LASTPIN (-1825 3550) SIG_NAME M_H_DQS_DN<7>
J 0
(-1815 3560);
DISPLAY 0.659574 (-1815 3560);
PAINT MONO (-1815 3560);
DISPLAY INVISIBLE (-1815 3560);
FORCEPROP 1 LASTPIN (-1825 3550) BN 7
J 2
(-1775 3560);
DISPLAY 0.617021 (-1775 3560);
PAINT PINK (-1775 3560);
FORCEPROP 2 LAST CDS_LIB mstr_standard
J 0
(-1775 3550);
DISPLAY 0.787234 (-1775 3550);
PAINT MONO (-1775 3550);
DISPLAY INVISIBLE (-1775 3550);
FORCEPROP 1 LAST BODY_TYPE PLUMBING
J 2
(-1775 3500);
DISPLAY 1.234043 (-1775 3500);
PAINT GREEN (-1775 3500);
DISPLAY INVISIBLE (-1775 3500);
FORCEPROP 1 LAST HDL_TAP TRUE
J 2
(-2100 3425);
DISPLAY 1.234043 (-2100 3425);
PAINT GREEN (-2100 3425);
DISPLAY INVISIBLE (-2100 3425);
FORCEPROP 1 LAST PATH I163
J 2
(-1773 3550);
DISPLAY 0.872340 (-1773 3550);
PAINT GREEN (-1773 3550);
DISPLAY INVISIBLE (-1773 3550);
FORCEADD TAP..6
R 2
(-1775 3750);
FORCEPROP 3 LASTPIN (-1825 3750) SIG_NAME M_H_DQS_DN<9>
J 0
(-1815 3760);
DISPLAY 0.659574 (-1815 3760);
PAINT MONO (-1815 3760);
DISPLAY INVISIBLE (-1815 3760);
FORCEPROP 1 LASTPIN (-1825 3750) BN 9
J 2
(-1775 3760);
DISPLAY 0.617021 (-1775 3760);
PAINT PINK (-1775 3760);
FORCEPROP 2 LAST CDS_LIB mstr_standard
J 0
(-1775 3750);
DISPLAY 0.787234 (-1775 3750);
PAINT MONO (-1775 3750);
DISPLAY INVISIBLE (-1775 3750);
FORCEPROP 1 LAST BODY_TYPE PLUMBING
J 2
(-1775 3700);
DISPLAY 1.234043 (-1775 3700);
PAINT GREEN (-1775 3700);
DISPLAY INVISIBLE (-1775 3700);
FORCEPROP 1 LAST HDL_TAP TRUE
J 2
(-2100 3625);
DISPLAY 1.234043 (-2100 3625);
PAINT GREEN (-2100 3625);
DISPLAY INVISIBLE (-2100 3625);
FORCEPROP 1 LAST PATH I164
J 2
(-1773 3750);
DISPLAY 0.872340 (-1773 3750);
PAINT GREEN (-1773 3750);
DISPLAY INVISIBLE (-1773 3750);
FORCEADD TAP..6
R 2
(-1775 3850);
FORCEPROP 3 LASTPIN (-1825 3850) SIG_NAME M_H_DQS_DN<10>
J 0
(-1815 3860);
DISPLAY 0.659574 (-1815 3860);
PAINT MONO (-1815 3860);
DISPLAY INVISIBLE (-1815 3860);
FORCEPROP 1 LASTPIN (-1825 3850) BN 10
J 2
(-1775 3860);
DISPLAY 0.617021 (-1775 3860);
PAINT PINK (-1775 3860);
FORCEPROP 2 LAST CDS_LIB mstr_standard
J 0
(-1775 3850);
DISPLAY 0.787234 (-1775 3850);
PAINT MONO (-1775 3850);
DISPLAY INVISIBLE (-1775 3850);
FORCEPROP 1 LAST BODY_TYPE PLUMBING
J 2
(-1775 3800);
DISPLAY 1.234043 (-1775 3800);
PAINT GREEN (-1775 3800);
DISPLAY INVISIBLE (-1775 3800);
FORCEPROP 1 LAST HDL_TAP TRUE
J 2
(-2100 3725);
DISPLAY 1.234043 (-2100 3725);
PAINT GREEN (-2100 3725);
DISPLAY INVISIBLE (-2100 3725);
FORCEPROP 1 LAST PATH I165
J 2
(-1773 3850);
DISPLAY 0.872340 (-1773 3850);
PAINT GREEN (-1773 3850);
DISPLAY INVISIBLE (-1773 3850);
FORCEADD TAP..6
R 2
(-1775 3950);
FORCEPROP 3 LASTPIN (-1825 3950) SIG_NAME M_H_DQS_DN<11>
J 0
(-1815 3960);
DISPLAY 0.659574 (-1815 3960);
PAINT MONO (-1815 3960);
DISPLAY INVISIBLE (-1815 3960);
FORCEPROP 1 LASTPIN (-1825 3950) BN 11
J 2
(-1775 3960);
DISPLAY 0.617021 (-1775 3960);
PAINT PINK (-1775 3960);
FORCEPROP 2 LAST CDS_LIB mstr_standard
J 0
(-1775 3950);
DISPLAY 0.787234 (-1775 3950);
PAINT MONO (-1775 3950);
DISPLAY INVISIBLE (-1775 3950);
FORCEPROP 1 LAST BODY_TYPE PLUMBING
J 2
(-1775 3900);
DISPLAY 1.234043 (-1775 3900);
PAINT GREEN (-1775 3900);
DISPLAY INVISIBLE (-1775 3900);
FORCEPROP 1 LAST HDL_TAP TRUE
J 2
(-2100 3825);
DISPLAY 1.234043 (-2100 3825);
PAINT GREEN (-2100 3825);
DISPLAY INVISIBLE (-2100 3825);
FORCEPROP 1 LAST PATH I166
J 2
(-1773 3950);
DISPLAY 0.872340 (-1773 3950);
PAINT GREEN (-1773 3950);
DISPLAY INVISIBLE (-1773 3950);
FORCEADD TAP..6
R 2
(-1775 4050);
FORCEPROP 3 LASTPIN (-1825 4050) SIG_NAME M_H_DQS_DN<12>
J 0
(-1815 4060);
DISPLAY 0.659574 (-1815 4060);
PAINT MONO (-1815 4060);
DISPLAY INVISIBLE (-1815 4060);
FORCEPROP 1 LASTPIN (-1825 4050) BN 12
J 2
(-1775 4060);
DISPLAY 0.617021 (-1775 4060);
PAINT PINK (-1775 4060);
FORCEPROP 2 LAST CDS_LIB mstr_standard
J 0
(-1775 4050);
DISPLAY 0.787234 (-1775 4050);
PAINT MONO (-1775 4050);
DISPLAY INVISIBLE (-1775 4050);
FORCEPROP 1 LAST BODY_TYPE PLUMBING
J 2
(-1775 4000);
DISPLAY 1.234043 (-1775 4000);
PAINT GREEN (-1775 4000);
DISPLAY INVISIBLE (-1775 4000);
FORCEPROP 1 LAST HDL_TAP TRUE
J 2
(-2100 3925);
DISPLAY 1.234043 (-2100 3925);
PAINT GREEN (-2100 3925);
DISPLAY INVISIBLE (-2100 3925);
FORCEPROP 1 LAST PATH I167
J 2
(-1773 4050);
DISPLAY 0.872340 (-1773 4050);
PAINT GREEN (-1773 4050);
DISPLAY INVISIBLE (-1773 4050);
FORCEADD TAP..6
R 2
(-1975 4300);
FORCEPROP 3 LASTPIN (-2025 4300) SIG_NAME M_H_DQS_DP<14>
J 0
(-2015 4310);
DISPLAY 0.659574 (-2015 4310);
PAINT MONO (-2015 4310);
DISPLAY INVISIBLE (-2015 4310);
FORCEPROP 1 LASTPIN (-2025 4300) BN 14
J 2
(-1975 4310);
DISPLAY 0.617021 (-1975 4310);
PAINT PINK (-1975 4310);
FORCEPROP 2 LAST CDS_LIB mstr_standard
J 0
(-1975 4300);
DISPLAY 0.787234 (-1975 4300);
PAINT MONO (-1975 4300);
DISPLAY INVISIBLE (-1975 4300);
FORCEPROP 1 LAST BODY_TYPE PLUMBING
J 2
(-1975 4250);
DISPLAY 1.234043 (-1975 4250);
PAINT GREEN (-1975 4250);
DISPLAY INVISIBLE (-1975 4250);
FORCEPROP 1 LAST HDL_TAP TRUE
J 2
(-2300 4175);
DISPLAY 1.234043 (-2300 4175);
PAINT GREEN (-2300 4175);
DISPLAY INVISIBLE (-2300 4175);
FORCEPROP 1 LAST PATH I168
J 2
(-1973 4300);
DISPLAY 0.872340 (-1973 4300);
PAINT GREEN (-1973 4300);
DISPLAY INVISIBLE (-1973 4300);
FORCEADD TAP..6
R 2
(-1975 4200);
FORCEPROP 3 LASTPIN (-2025 4200) SIG_NAME M_H_DQS_DP<13>
J 0
(-2015 4210);
DISPLAY 0.659574 (-2015 4210);
PAINT MONO (-2015 4210);
DISPLAY INVISIBLE (-2015 4210);
FORCEPROP 1 LASTPIN (-2025 4200) BN 13
J 2
(-1975 4210);
DISPLAY 0.617021 (-1975 4210);
PAINT PINK (-1975 4210);
FORCEPROP 2 LAST CDS_LIB mstr_standard
J 0
(-1975 4200);
DISPLAY 0.787234 (-1975 4200);
PAINT MONO (-1975 4200);
DISPLAY INVISIBLE (-1975 4200);
FORCEPROP 1 LAST BODY_TYPE PLUMBING
J 2
(-1975 4150);
DISPLAY 1.234043 (-1975 4150);
PAINT GREEN (-1975 4150);
DISPLAY INVISIBLE (-1975 4150);
FORCEPROP 1 LAST HDL_TAP TRUE
J 2
(-2300 4075);
DISPLAY 1.234043 (-2300 4075);
PAINT GREEN (-2300 4075);
DISPLAY INVISIBLE (-2300 4075);
FORCEPROP 1 LAST PATH I169
J 2
(-1973 4200);
DISPLAY 0.872340 (-1973 4200);
PAINT GREEN (-1973 4200);
DISPLAY INVISIBLE (-1973 4200);
FORCEADD OFFPAGE..1
(-6625 2900);
FORCEPROP 2 LAST $XR1 79 
J 0
(-6936 2900);
DISPLAY 0.638298 (-6936 2900);
PAINT MONO (-6936 2900);
FORCEPROP 2 LAST $XR0 58 
J 0
(-6846 2900);
DISPLAY 0.638298 (-6846 2900);
PAINT MONO (-6846 2900);
FORCEPROP 2 LAST CDS_LIB mstr_standard
J 0
(-6625 2900);
DISPLAY 0.787234 (-6625 2900);
PAINT MONO (-6625 2900);
DISPLAY INVISIBLE (-6625 2900);
FORCEPROP 1 LAST OFFPAGE TRUE
J 0
(-6300 2775);
DISPLAY 0.936170 (-6300 2775);
PAINT GREEN (-6300 2775);
DISPLAY INVISIBLE (-6300 2775);
FORCEPROP 1 LAST COMMENT_BODY TRUE
J 0
(-6500 2800);
DISPLAY 0.936170 (-6500 2800);
PAINT GREEN (-6500 2800);
DISPLAY INVISIBLE (-6500 2800);
FORCEPROP 2 LAST PATH I17
J 0
(-6875 2950);
DISPLAY 1.021277 (-6875 2950);
PAINT ORANGE (-6875 2950);
DISPLAY INVISIBLE (-6875 2950);
FORCEADD TAP..6
R 2
(-1975 4100);
FORCEPROP 3 LASTPIN (-2025 4100) SIG_NAME M_H_DQS_DP<12>
J 0
(-2015 4110);
DISPLAY 0.659574 (-2015 4110);
PAINT MONO (-2015 4110);
DISPLAY INVISIBLE (-2015 4110);
FORCEPROP 1 LASTPIN (-2025 4100) BN 12
J 2
(-1975 4110);
DISPLAY 0.617021 (-1975 4110);
PAINT PINK (-1975 4110);
FORCEPROP 2 LAST CDS_LIB mstr_standard
J 0
(-1975 4100);
DISPLAY 0.787234 (-1975 4100);
PAINT MONO (-1975 4100);
DISPLAY INVISIBLE (-1975 4100);
FORCEPROP 1 LAST BODY_TYPE PLUMBING
J 2
(-1975 4050);
DISPLAY 1.234043 (-1975 4050);
PAINT GREEN (-1975 4050);
DISPLAY INVISIBLE (-1975 4050);
FORCEPROP 1 LAST HDL_TAP TRUE
J 2
(-2300 3975);
DISPLAY 1.234043 (-2300 3975);
PAINT GREEN (-2300 3975);
DISPLAY INVISIBLE (-2300 3975);
FORCEPROP 1 LAST PATH I170
J 2
(-1973 4100);
DISPLAY 0.872340 (-1973 4100);
PAINT GREEN (-1973 4100);
DISPLAY INVISIBLE (-1973 4100);
FORCEADD TAP..6
R 2
(-1975 4400);
FORCEPROP 3 LASTPIN (-2025 4400) SIG_NAME M_H_DQS_DP<15>
J 0
(-2015 4410);
DISPLAY 0.659574 (-2015 4410);
PAINT MONO (-2015 4410);
DISPLAY INVISIBLE (-2015 4410);
FORCEPROP 1 LASTPIN (-2025 4400) BN 15
J 2
(-1975 4410);
DISPLAY 0.617021 (-1975 4410);
PAINT PINK (-1975 4410);
FORCEPROP 2 LAST CDS_LIB mstr_standard
J 0
(-1975 4400);
DISPLAY 0.787234 (-1975 4400);
PAINT MONO (-1975 4400);
DISPLAY INVISIBLE (-1975 4400);
FORCEPROP 1 LAST BODY_TYPE PLUMBING
J 2
(-1975 4350);
DISPLAY 1.234043 (-1975 4350);
PAINT GREEN (-1975 4350);
DISPLAY INVISIBLE (-1975 4350);
FORCEPROP 1 LAST HDL_TAP TRUE
J 2
(-2300 4275);
DISPLAY 1.234043 (-2300 4275);
PAINT GREEN (-2300 4275);
DISPLAY INVISIBLE (-2300 4275);
FORCEPROP 1 LAST PATH I171
J 2
(-1973 4400);
DISPLAY 0.872340 (-1973 4400);
PAINT GREEN (-1973 4400);
DISPLAY INVISIBLE (-1973 4400);
FORCEADD TAP..6
R 2
(-1975 4500);
FORCEPROP 3 LASTPIN (-2025 4500) SIG_NAME M_H_DQS_DP<16>
J 0
(-2015 4510);
DISPLAY 0.659574 (-2015 4510);
PAINT MONO (-2015 4510);
DISPLAY INVISIBLE (-2015 4510);
FORCEPROP 1 LASTPIN (-2025 4500) BN 16
J 2
(-1975 4510);
DISPLAY 0.617021 (-1975 4510);
PAINT PINK (-1975 4510);
FORCEPROP 2 LAST CDS_LIB mstr_standard
J 0
(-1975 4500);
DISPLAY 0.787234 (-1975 4500);
PAINT MONO (-1975 4500);
DISPLAY INVISIBLE (-1975 4500);
FORCEPROP 1 LAST BODY_TYPE PLUMBING
J 2
(-1975 4450);
DISPLAY 1.234043 (-1975 4450);
PAINT GREEN (-1975 4450);
DISPLAY INVISIBLE (-1975 4450);
FORCEPROP 1 LAST HDL_TAP TRUE
J 2
(-2300 4375);
DISPLAY 1.234043 (-2300 4375);
PAINT GREEN (-2300 4375);
DISPLAY INVISIBLE (-2300 4375);
FORCEPROP 1 LAST PATH I172
J 2
(-1973 4500);
DISPLAY 0.872340 (-1973 4500);
PAINT GREEN (-1973 4500);
DISPLAY INVISIBLE (-1973 4500);
FORCEADD TAP..6
R 2
(-1775 4150);
FORCEPROP 3 LASTPIN (-1825 4150) SIG_NAME M_H_DQS_DN<13>
J 0
(-1815 4160);
DISPLAY 0.659574 (-1815 4160);
PAINT MONO (-1815 4160);
DISPLAY INVISIBLE (-1815 4160);
FORCEPROP 1 LASTPIN (-1825 4150) BN 13
J 2
(-1775 4160);
DISPLAY 0.617021 (-1775 4160);
PAINT PINK (-1775 4160);
FORCEPROP 2 LAST CDS_LIB mstr_standard
J 0
(-1775 4150);
DISPLAY 0.787234 (-1775 4150);
PAINT MONO (-1775 4150);
DISPLAY INVISIBLE (-1775 4150);
FORCEPROP 1 LAST BODY_TYPE PLUMBING
J 2
(-1775 4100);
DISPLAY 1.234043 (-1775 4100);
PAINT GREEN (-1775 4100);
DISPLAY INVISIBLE (-1775 4100);
FORCEPROP 1 LAST HDL_TAP TRUE
J 2
(-2100 4025);
DISPLAY 1.234043 (-2100 4025);
PAINT GREEN (-2100 4025);
DISPLAY INVISIBLE (-2100 4025);
FORCEPROP 1 LAST PATH I173
J 2
(-1773 4150);
DISPLAY 0.872340 (-1773 4150);
PAINT GREEN (-1773 4150);
DISPLAY INVISIBLE (-1773 4150);
FORCEADD TAP..6
R 2
(-1775 4250);
FORCEPROP 3 LASTPIN (-1825 4250) SIG_NAME M_H_DQS_DN<14>
J 0
(-1815 4260);
DISPLAY 0.659574 (-1815 4260);
PAINT MONO (-1815 4260);
DISPLAY INVISIBLE (-1815 4260);
FORCEPROP 1 LASTPIN (-1825 4250) BN 14
J 2
(-1775 4260);
DISPLAY 0.617021 (-1775 4260);
PAINT PINK (-1775 4260);
FORCEPROP 2 LAST CDS_LIB mstr_standard
J 0
(-1775 4250);
DISPLAY 0.787234 (-1775 4250);
PAINT MONO (-1775 4250);
DISPLAY INVISIBLE (-1775 4250);
FORCEPROP 1 LAST BODY_TYPE PLUMBING
J 2
(-1775 4200);
DISPLAY 1.234043 (-1775 4200);
PAINT GREEN (-1775 4200);
DISPLAY INVISIBLE (-1775 4200);
FORCEPROP 1 LAST HDL_TAP TRUE
J 2
(-2100 4125);
DISPLAY 1.234043 (-2100 4125);
PAINT GREEN (-2100 4125);
DISPLAY INVISIBLE (-2100 4125);
FORCEPROP 1 LAST PATH I174
J 2
(-1773 4250);
DISPLAY 0.872340 (-1773 4250);
PAINT GREEN (-1773 4250);
DISPLAY INVISIBLE (-1773 4250);
FORCEADD TAP..6
R 2
(-1775 4350);
FORCEPROP 3 LASTPIN (-1825 4350) SIG_NAME M_H_DQS_DN<15>
J 0
(-1815 4360);
DISPLAY 0.659574 (-1815 4360);
PAINT MONO (-1815 4360);
DISPLAY INVISIBLE (-1815 4360);
FORCEPROP 1 LASTPIN (-1825 4350) BN 15
J 2
(-1775 4360);
DISPLAY 0.617021 (-1775 4360);
PAINT PINK (-1775 4360);
FORCEPROP 2 LAST CDS_LIB mstr_standard
J 0
(-1775 4350);
DISPLAY 0.787234 (-1775 4350);
PAINT MONO (-1775 4350);
DISPLAY INVISIBLE (-1775 4350);
FORCEPROP 1 LAST BODY_TYPE PLUMBING
J 2
(-1775 4300);
DISPLAY 1.234043 (-1775 4300);
PAINT GREEN (-1775 4300);
DISPLAY INVISIBLE (-1775 4300);
FORCEPROP 1 LAST HDL_TAP TRUE
J 2
(-2100 4225);
DISPLAY 1.234043 (-2100 4225);
PAINT GREEN (-2100 4225);
DISPLAY INVISIBLE (-2100 4225);
FORCEPROP 1 LAST PATH I175
J 2
(-1773 4350);
DISPLAY 0.872340 (-1773 4350);
PAINT GREEN (-1773 4350);
DISPLAY INVISIBLE (-1773 4350);
FORCEADD TAP..6
R 2
(-1775 4450);
FORCEPROP 3 LASTPIN (-1825 4450) SIG_NAME M_H_DQS_DN<16>
J 0
(-1815 4460);
DISPLAY 0.659574 (-1815 4460);
PAINT MONO (-1815 4460);
DISPLAY INVISIBLE (-1815 4460);
FORCEPROP 1 LASTPIN (-1825 4450) BN 16
J 2
(-1775 4460);
DISPLAY 0.617021 (-1775 4460);
PAINT PINK (-1775 4460);
FORCEPROP 2 LAST CDS_LIB mstr_standard
J 0
(-1775 4450);
DISPLAY 0.787234 (-1775 4450);
PAINT MONO (-1775 4450);
DISPLAY INVISIBLE (-1775 4450);
FORCEPROP 1 LAST BODY_TYPE PLUMBING
J 2
(-1775 4400);
DISPLAY 1.234043 (-1775 4400);
PAINT GREEN (-1775 4400);
DISPLAY INVISIBLE (-1775 4400);
FORCEPROP 1 LAST HDL_TAP TRUE
J 2
(-2100 4325);
DISPLAY 1.234043 (-2100 4325);
PAINT GREEN (-2100 4325);
DISPLAY INVISIBLE (-2100 4325);
FORCEPROP 1 LAST PATH I176
J 2
(-1773 4450);
DISPLAY 0.872340 (-1773 4450);
PAINT GREEN (-1773 4450);
DISPLAY INVISIBLE (-1773 4450);
FORCEADD TAP..6
R 2
(-1775 4550);
FORCEPROP 3 LASTPIN (-1825 4550) SIG_NAME M_H_DQS_DN<17>
J 0
(-1815 4560);
DISPLAY 0.659574 (-1815 4560);
PAINT MONO (-1815 4560);
DISPLAY INVISIBLE (-1815 4560);
FORCEPROP 1 LASTPIN (-1825 4550) BN 17
J 2
(-1775 4560);
DISPLAY 0.617021 (-1775 4560);
PAINT PINK (-1775 4560);
FORCEPROP 2 LAST CDS_LIB mstr_standard
J 2
(-1775 4550);
DISPLAY 0.787234 (-1775 4550);
PAINT MONO (-1775 4550);
DISPLAY INVISIBLE (-1775 4550);
FORCEPROP 1 LAST BODY_TYPE PLUMBING
J 2
(-1775 4500);
DISPLAY 1.234043 (-1775 4500);
PAINT GREEN (-1775 4500);
DISPLAY INVISIBLE (-1775 4500);
FORCEPROP 1 LAST HDL_TAP TRUE
J 2
(-2100 4425);
DISPLAY 1.234043 (-2100 4425);
PAINT GREEN (-2100 4425);
DISPLAY INVISIBLE (-2100 4425);
FORCEPROP 1 LAST PATH I177
J 2
(-1773 4550);
DISPLAY 0.872340 (-1773 4550);
PAINT GREEN (-1773 4550);
DISPLAY INVISIBLE (-1773 4550);
FORCEADD TAP..6
R 2
(-1975 4600);
FORCEPROP 3 LASTPIN (-2025 4600) SIG_NAME M_H_DQS_DP<17>
J 0
(-2015 4610);
DISPLAY 0.659574 (-2015 4610);
PAINT MONO (-2015 4610);
DISPLAY INVISIBLE (-2015 4610);
FORCEPROP 1 LASTPIN (-2025 4600) BN 17
J 2
(-1975 4610);
DISPLAY 0.617021 (-1975 4610);
PAINT PINK (-1975 4610);
FORCEPROP 2 LAST CDS_LIB mstr_standard
J 2
(-1975 4600);
DISPLAY 0.787234 (-1975 4600);
PAINT MONO (-1975 4600);
DISPLAY INVISIBLE (-1975 4600);
FORCEPROP 1 LAST BODY_TYPE PLUMBING
J 2
(-1975 4550);
DISPLAY 1.234043 (-1975 4550);
PAINT GREEN (-1975 4550);
DISPLAY INVISIBLE (-1975 4550);
FORCEPROP 1 LAST HDL_TAP TRUE
J 2
(-2300 4475);
DISPLAY 1.234043 (-2300 4475);
PAINT GREEN (-2300 4475);
DISPLAY INVISIBLE (-2300 4475);
FORCEPROP 1 LAST PATH I178
J 2
(-1973 4600);
DISPLAY 0.872340 (-1973 4600);
PAINT GREEN (-1973 4600);
DISPLAY INVISIBLE (-1973 4600);
FORCEADD OFFPAGE..3
(-1075 4600);
FORCEPROP 2 LAST $XR1 79 
J 0
(-771 4600);
DISPLAY 0.638298 (-771 4600);
PAINT MONO (-771 4600);
FORCEPROP 2 LAST $XR0 58 
J 0
(-861 4600);
DISPLAY 0.638298 (-861 4600);
PAINT MONO (-861 4600);
FORCEPROP 2 LAST CDS_LIB mstr_standard
J 0
(-1075 4600);
DISPLAY 0.787234 (-1075 4600);
PAINT MONO (-1075 4600);
DISPLAY INVISIBLE (-1075 4600);
FORCEPROP 1 LAST OFFPAGE TRUE
J 0
(-750 4475);
DISPLAY 0.936170 (-750 4475);
PAINT GREEN (-750 4475);
DISPLAY INVISIBLE (-750 4475);
FORCEPROP 1 LAST COMMENT_BODY TRUE
J 0
(-1125 4500);
DISPLAY 0.936170 (-1125 4500);
PAINT GREEN (-1125 4500);
DISPLAY INVISIBLE (-1125 4500);
FORCEPROP 2 LAST PATH I179
J 0
(-850 4650);
DISPLAY 1.021277 (-850 4650);
PAINT ORANGE (-850 4650);
DISPLAY INVISIBLE (-850 4650);
FORCEADD OFFPAGE..1
(-6625 2950);
FORCEPROP 2 LAST $XR1 79 
J 0
(-6936 2950);
DISPLAY 0.638298 (-6936 2950);
PAINT MONO (-6936 2950);
FORCEPROP 2 LAST $XR0 58 
J 0
(-6846 2950);
DISPLAY 0.638298 (-6846 2950);
PAINT MONO (-6846 2950);
FORCEPROP 2 LAST CDS_LIB mstr_standard
J 0
(-6625 2950);
DISPLAY 0.787234 (-6625 2950);
PAINT MONO (-6625 2950);
DISPLAY INVISIBLE (-6625 2950);
FORCEPROP 1 LAST OFFPAGE TRUE
J 0
(-6300 2825);
DISPLAY 0.936170 (-6300 2825);
PAINT GREEN (-6300 2825);
DISPLAY INVISIBLE (-6300 2825);
FORCEPROP 1 LAST COMMENT_BODY TRUE
J 0
(-6500 2850);
DISPLAY 0.936170 (-6500 2850);
PAINT GREEN (-6500 2850);
DISPLAY INVISIBLE (-6500 2850);
FORCEPROP 2 LAST PATH I18
J 0
(-6875 3000);
DISPLAY 1.021277 (-6875 3000);
PAINT ORANGE (-6875 3000);
DISPLAY INVISIBLE (-6875 3000);
FORCEADD OFFPAGE..3
(-1075 4650);
FORCEPROP 2 LAST $XR1 79 
J 0
(-771 4650);
DISPLAY 0.638298 (-771 4650);
PAINT MONO (-771 4650);
FORCEPROP 2 LAST $XR0 58 
J 0
(-861 4650);
DISPLAY 0.638298 (-861 4650);
PAINT MONO (-861 4650);
FORCEPROP 2 LAST CDS_LIB mstr_standard
J 0
(-1075 4650);
DISPLAY 0.787234 (-1075 4650);
PAINT MONO (-1075 4650);
DISPLAY INVISIBLE (-1075 4650);
FORCEPROP 1 LAST OFFPAGE TRUE
J 0
(-750 4525);
DISPLAY 0.936170 (-750 4525);
PAINT GREEN (-750 4525);
DISPLAY INVISIBLE (-750 4525);
FORCEPROP 1 LAST COMMENT_BODY TRUE
J 0
(-1125 4550);
DISPLAY 0.936170 (-1125 4550);
PAINT GREEN (-1125 4550);
DISPLAY INVISIBLE (-1125 4550);
FORCEPROP 2 LAST PATH I180
J 0
(-850 4700);
DISPLAY 1.021277 (-850 4700);
PAINT ORANGE (-850 4700);
DISPLAY INVISIBLE (-850 4700);
FORCEADD P12V_NVDIMM_GHJ..1
(-2375 2425);
FORCEPROP 3 LASTPIN (-2375 2375) SIG_NAME P12V_NVDIMM_GHJ\g
J 0
(-2365 2385);
DISPLAY 0.659574 (-2365 2385);
PAINT MONO (-2365 2385);
DISPLAY INVISIBLE (-2365 2385);
FORCEPROP 1 LAST VOLTAGE 12.0
J 0
(-2420 2382);
DISPLAY 0.340426 (-2420 2382);
PAINT SKYBLUE (-2420 2382);
DISPLAY INVISIBLE (-2420 2382);
FORCEPROP 2 LAST CDS_LIB mstr_symbols
J 0
(-2375 2425);
PAINT ORANGE (-2375 2425);
DISPLAY INVISIBLE (-2375 2425);
FORCEPROP 1 LAST BODY_TYPE PLUMBING
J 0
(-2420 2382);
DISPLAY 0.340426 (-2420 2382);
PAINT GREEN (-2420 2382);
DISPLAY INVISIBLE (-2420 2382);
FORCEPROP 1 LAST PATH I181
J 0
(-2325 2450);
DISPLAY 0.872340 (-2325 2450);
PAINT AQUA (-2325 2450);
DISPLAY INVISIBLE (-2325 2450);
FORCEPROP 1 LAST HDL_POWER P12V_NVDIMM_GHJ
J 1
(-2375 2475);
DISPLAY 0.872340 (-2375 2475);
PAINT GREEN (-2375 2475);
DISPLAY INVISIBLE (-2375 2475);
FORCEADD OFFPAGE..1
(-6625 3200);
FORCEPROP 2 LAST $XR1 79 
J 0
(-6936 3200);
DISPLAY 0.638298 (-6936 3200);
PAINT MONO (-6936 3200);
FORCEPROP 2 LAST $XR0 58 
J 0
(-6846 3200);
DISPLAY 0.638298 (-6846 3200);
PAINT MONO (-6846 3200);
FORCEPROP 2 LAST CDS_LIB mstr_standard
J 0
(-6625 3200);
DISPLAY 0.787234 (-6625 3200);
PAINT MONO (-6625 3200);
DISPLAY INVISIBLE (-6625 3200);
FORCEPROP 1 LAST OFFPAGE TRUE
J 0
(-6300 3075);
DISPLAY 0.936170 (-6300 3075);
PAINT GREEN (-6300 3075);
DISPLAY INVISIBLE (-6300 3075);
FORCEPROP 1 LAST COMMENT_BODY TRUE
J 0
(-6500 3100);
DISPLAY 0.936170 (-6500 3100);
PAINT GREEN (-6500 3100);
DISPLAY INVISIBLE (-6500 3100);
FORCEPROP 2 LAST PATH I19
J 0
(-6875 3250);
DISPLAY 1.021277 (-6875 3250);
PAINT ORANGE (-6875 3250);
DISPLAY INVISIBLE (-6875 3250);
FORCEADD OFFPAGE..1
(-7325 1200);
FORCEPROP 2 LAST $XR1 79 
J 0
(-7667 1200);
DISPLAY 0.638298 (-7667 1200);
PAINT MONO (-7667 1200);
FORCEPROP 2 LAST $XR0 100 
J 0
(-7577 1200);
DISPLAY 0.638298 (-7577 1200);
PAINT MONO (-7577 1200);
FORCEPROP 2 LAST CDS_LIB mstr_standard
J 0
(-7325 1200);
DISPLAY 0.787234 (-7325 1200);
PAINT MONO (-7325 1200);
DISPLAY INVISIBLE (-7325 1200);
FORCEPROP 1 LAST OFFPAGE TRUE
J 0
(-7000 1075);
DISPLAY 0.936170 (-7000 1075);
PAINT GREEN (-7000 1075);
DISPLAY INVISIBLE (-7000 1075);
FORCEPROP 1 LAST COMMENT_BODY TRUE
J 0
(-7200 1100);
DISPLAY 0.936170 (-7200 1100);
PAINT GREEN (-7200 1100);
DISPLAY INVISIBLE (-7200 1100);
FORCEPROP 2 LAST PATH I2
J 0
(-7525 1250);
DISPLAY 1.021277 (-7525 1250);
PAINT ORANGE (-7525 1250);
DISPLAY INVISIBLE (-7525 1250);
FORCEADD OFFPAGE..1
(-6625 3150);
FORCEPROP 2 LAST $XR1 79 
J 0
(-6936 3150);
DISPLAY 0.638298 (-6936 3150);
PAINT MONO (-6936 3150);
FORCEPROP 2 LAST $XR0 58 
J 0
(-6846 3150);
DISPLAY 0.638298 (-6846 3150);
PAINT MONO (-6846 3150);
FORCEPROP 2 LAST CDS_LIB mstr_standard
J 0
(-6625 3150);
DISPLAY 0.787234 (-6625 3150);
PAINT MONO (-6625 3150);
DISPLAY INVISIBLE (-6625 3150);
FORCEPROP 1 LAST OFFPAGE TRUE
J 0
(-6300 3025);
DISPLAY 0.936170 (-6300 3025);
PAINT GREEN (-6300 3025);
DISPLAY INVISIBLE (-6300 3025);
FORCEPROP 1 LAST COMMENT_BODY TRUE
J 0
(-6500 3050);
DISPLAY 0.936170 (-6500 3050);
PAINT GREEN (-6500 3050);
DISPLAY INVISIBLE (-6500 3050);
FORCEPROP 2 LAST PATH I20
J 0
(-6875 3200);
DISPLAY 1.021277 (-6875 3200);
PAINT ORANGE (-6875 3200);
DISPLAY INVISIBLE (-6875 3200);
FORCEADD OFFPAGE..1
(-6625 3350);
FORCEPROP 2 LAST $XR1 79 
J 0
(-6936 3350);
DISPLAY 0.638298 (-6936 3350);
PAINT MONO (-6936 3350);
FORCEPROP 2 LAST $XR0 58 
J 0
(-6846 3350);
DISPLAY 0.638298 (-6846 3350);
PAINT MONO (-6846 3350);
FORCEPROP 2 LAST CDS_LIB mstr_standard
J 0
(-6625 3350);
DISPLAY 0.787234 (-6625 3350);
PAINT MONO (-6625 3350);
DISPLAY INVISIBLE (-6625 3350);
FORCEPROP 1 LAST OFFPAGE TRUE
J 0
(-6300 3225);
DISPLAY 0.936170 (-6300 3225);
PAINT GREEN (-6300 3225);
DISPLAY INVISIBLE (-6300 3225);
FORCEPROP 1 LAST COMMENT_BODY TRUE
J 0
(-6500 3250);
DISPLAY 0.936170 (-6500 3250);
PAINT GREEN (-6500 3250);
DISPLAY INVISIBLE (-6500 3250);
FORCEPROP 2 LAST PATH I21
J 0
(-6875 3400);
DISPLAY 1.021277 (-6875 3400);
PAINT ORANGE (-6875 3400);
DISPLAY INVISIBLE (-6875 3400);
FORCEADD OFFPAGE..1
(-6625 3450);
FORCEPROP 2 LAST $XR1 79 
J 0
(-6936 3450);
DISPLAY 0.638298 (-6936 3450);
PAINT MONO (-6936 3450);
FORCEPROP 2 LAST $XR0 58 
J 0
(-6846 3450);
DISPLAY 0.638298 (-6846 3450);
PAINT MONO (-6846 3450);
FORCEPROP 2 LAST CDS_LIB mstr_standard
J 0
(-6625 3450);
DISPLAY 0.787234 (-6625 3450);
PAINT MONO (-6625 3450);
DISPLAY INVISIBLE (-6625 3450);
FORCEPROP 1 LAST OFFPAGE TRUE
J 0
(-6300 3325);
DISPLAY 0.936170 (-6300 3325);
PAINT GREEN (-6300 3325);
DISPLAY INVISIBLE (-6300 3325);
FORCEPROP 1 LAST COMMENT_BODY TRUE
J 0
(-6500 3350);
DISPLAY 0.936170 (-6500 3350);
PAINT GREEN (-6500 3350);
DISPLAY INVISIBLE (-6500 3350);
FORCEPROP 2 LAST PATH I22
J 0
(-6875 3500);
DISPLAY 1.021277 (-6875 3500);
PAINT ORANGE (-6875 3500);
DISPLAY INVISIBLE (-6875 3500);
FORCEADD OFFPAGE..1
(-6625 4400);
FORCEPROP 2 LAST $XR1 79 
J 0
(-6936 4400);
DISPLAY 0.638298 (-6936 4400);
PAINT MONO (-6936 4400);
FORCEPROP 2 LAST $XR0 58 
J 0
(-6846 4400);
DISPLAY 0.638298 (-6846 4400);
PAINT MONO (-6846 4400);
FORCEPROP 2 LAST CDS_LIB mstr_standard
J 0
(-6625 4400);
DISPLAY 0.787234 (-6625 4400);
PAINT MONO (-6625 4400);
DISPLAY INVISIBLE (-6625 4400);
FORCEPROP 1 LAST OFFPAGE TRUE
J 0
(-6300 4275);
DISPLAY 0.936170 (-6300 4275);
PAINT GREEN (-6300 4275);
DISPLAY INVISIBLE (-6300 4275);
FORCEPROP 1 LAST COMMENT_BODY TRUE
J 0
(-6500 4300);
DISPLAY 0.936170 (-6500 4300);
PAINT GREEN (-6500 4300);
DISPLAY INVISIBLE (-6500 4300);
FORCEPROP 2 LAST PATH I23
J 0
(-6875 4450);
DISPLAY 1.021277 (-6875 4450);
PAINT ORANGE (-6875 4450);
DISPLAY INVISIBLE (-6875 4450);
FORCEADD SCONN288_H44441003..1
(-5225 2700);
FORCEPROP 2 LASTPIN (-5725 4350) $PN 234
J 2
(-5735 4360);
DISPLAY 0.617021 (-5735 4360);
PAINT ORANGE (-5735 4360);
FORCEPROP 1 LAST PART_NUMBER H44441-003
J 0
(-5675 700);
DISPLAY 0.617021 (-5675 700);
PAINT BLUE (-5675 700);
FORCEPROP 1 LAST MATERIAL SCONN
J 0
(-5675 4550);
DISPLAY 0.617021 (-5675 4550);
PAINT SKYBLUE (-5675 4550);
FORCEPROP 2 LASTPIN (-5725 1200) $PN 146
J 2
(-5735 1210);
DISPLAY 0.617021 (-5735 1210);
PAINT ORANGE (-5735 1210);
FORCEPROP 2 LASTPIN (-5725 1550) $PN 284
J 2
(-5735 1560);
DISPLAY 0.617021 (-5735 1560);
PAINT ORANGE (-5735 1560);
FORCEPROP 2 LASTPIN (-5725 1350) $PN 285
J 2
(-5735 1360);
DISPLAY 0.617021 (-5735 1360);
PAINT ORANGE (-5735 1360);
FORCEPROP 2 LASTPIN (-5725 1300) $PN 141
J 2
(-5735 1310);
DISPLAY 0.617021 (-5735 1310);
PAINT ORANGE (-5735 1310);
FORCEPROP 2 LASTPIN (-5725 900) $PN 230
J 2
(-5735 910);
DISPLAY 0.617021 (-5735 910);
PAINT ORANGE (-5735 910);
FORCEPROP 2 LASTPIN (-5725 1500) $PN 238
J 2
(-5735 1510);
DISPLAY 0.617021 (-5735 1510);
PAINT ORANGE (-5735 1510);
FORCEPROP 2 LASTPIN (-5725 1450) $PN 140
J 2
(-5735 1460);
DISPLAY 0.617021 (-5735 1460);
PAINT ORANGE (-5735 1460);
FORCEPROP 2 LASTPIN (-5725 1400) $PN 139
J 2
(-5735 1410);
DISPLAY 0.617021 (-5735 1410);
PAINT ORANGE (-5735 1410);
FORCEPROP 2 LASTPIN (-5725 2850) $PN 237
J 2
(-5735 2860);
DISPLAY 0.617021 (-5735 2860);
PAINT ORANGE (-5735 2860);
FORCEPROP 2 LASTPIN (-5725 2800) $PN 93
J 2
(-5735 2810);
DISPLAY 0.617021 (-5735 2810);
PAINT ORANGE (-5735 2810);
FORCEPROP 2 LASTPIN (-5725 2750) $PN 89
J 2
(-5735 2760);
DISPLAY 0.617021 (-5735 2760);
PAINT ORANGE (-5735 2760);
FORCEPROP 2 LASTPIN (-5725 2700) $PN 84
J 2
(-5735 2710);
DISPLAY 0.617021 (-5735 2710);
PAINT ORANGE (-5735 2710);
FORCEPROP 2 LASTPIN (-5725 1100) $PN 144
J 2
(-5735 1110);
DISPLAY 0.617021 (-5735 1110);
PAINT ORANGE (-5735 1110);
FORCEPROP 2 LASTPIN (-5725 1050) $PN 227
J 2
(-5735 1060);
DISPLAY 0.617021 (-5735 1060);
PAINT ORANGE (-5735 1060);
FORCEPROP 2 LASTPIN (-5725 1000) $PN 205
J 2
(-5735 1010);
DISPLAY 0.617021 (-5735 1010);
PAINT ORANGE (-5735 1010);
FORCEPROP 2 LASTPIN (-5725 1800) $PN 58
J 2
(-5735 1810);
DISPLAY 0.617021 (-5735 1810);
PAINT ORANGE (-5735 1810);
FORCEPROP 2 LASTPIN (-5725 1850) $PN 222
J 2
(-5735 1860);
DISPLAY 0.617021 (-5735 1860);
PAINT ORANGE (-5735 1860);
FORCEPROP 2 LASTPIN (-5725 2450) $PN 91
J 2
(-5735 2460);
DISPLAY 0.617021 (-5735 2460);
PAINT ORANGE (-5735 2460);
FORCEPROP 2 LASTPIN (-5725 2400) $PN 87
J 2
(-5735 2410);
DISPLAY 0.617021 (-5735 2410);
PAINT ORANGE (-5735 2410);
FORCEPROP 2 LASTPIN (-5725 1750) $PN 78
J 2
(-5735 1760);
DISPLAY 0.617021 (-5735 1760);
PAINT ORANGE (-5735 1760);
FORCEPROP 2 LASTPIN (-4725 4250) $PN 273
J 0
(-4715 4260);
DISPLAY 0.617021 (-4715 4260);
PAINT ORANGE (-4715 4260);
FORCEPROP 2 LASTPIN (-4725 4150) $PN 282
J 0
(-4715 4160);
DISPLAY 0.617021 (-4715 4160);
PAINT ORANGE (-4715 4160);
FORCEPROP 2 LASTPIN (-4725 3950) $PN 269
J 0
(-4715 3960);
DISPLAY 0.617021 (-4715 3960);
PAINT ORANGE (-4715 3960);
FORCEPROP 2 LASTPIN (-4725 3800) $PN 117
J 0
(-4715 3810);
DISPLAY 0.617021 (-4715 3810);
PAINT ORANGE (-4715 3810);
FORCEPROP 2 LASTPIN (-4725 3750) $PN 271
J 0
(-4715 3760);
DISPLAY 0.617021 (-4715 3760);
PAINT ORANGE (-4715 3760);
FORCEPROP 2 LASTPIN (-4725 3700) $PN 126
J 0
(-4715 3710);
DISPLAY 0.617021 (-4715 3710);
PAINT ORANGE (-4715 3710);
FORCEPROP 2 LASTPIN (-4725 3650) $PN 264
J 0
(-4715 3660);
DISPLAY 0.617021 (-4715 3660);
PAINT ORANGE (-4715 3660);
FORCEPROP 2 LASTPIN (-4725 3600) $PN 119
J 0
(-4715 3610);
DISPLAY 0.617021 (-4715 3610);
PAINT ORANGE (-4715 3610);
FORCEPROP 2 LASTPIN (-4725 3500) $PN 113
J 0
(-4715 3510);
DISPLAY 0.617021 (-4715 3510);
PAINT ORANGE (-4715 3510);
FORCEPROP 2 LASTPIN (-4725 3450) $PN 251
J 0
(-4715 3460);
DISPLAY 0.617021 (-4715 3460);
PAINT ORANGE (-4715 3460);
FORCEPROP 2 LASTPIN (-4725 3400) $PN 106
J 0
(-4715 3410);
DISPLAY 0.617021 (-4715 3410);
PAINT ORANGE (-4715 3410);
FORCEPROP 2 LASTPIN (-4725 3350) $PN 260
J 0
(-4715 3360);
DISPLAY 0.617021 (-4715 3360);
PAINT ORANGE (-4715 3360);
FORCEPROP 2 LASTPIN (-4725 3300) $PN 115
J 0
(-4715 3310);
DISPLAY 0.617021 (-4715 3310);
PAINT ORANGE (-4715 3310);
FORCEPROP 2 LASTPIN (-4725 3250) $PN 253
J 0
(-4715 3260);
DISPLAY 0.617021 (-4715 3260);
PAINT ORANGE (-4715 3260);
FORCEPROP 2 LASTPIN (-4725 3200) $PN 108
J 0
(-4715 3210);
DISPLAY 0.617021 (-4715 3210);
PAINT ORANGE (-4715 3210);
FORCEPROP 2 LASTPIN (-4725 3150) $PN 247
J 0
(-4715 3160);
DISPLAY 0.617021 (-4715 3160);
PAINT ORANGE (-4715 3160);
FORCEPROP 2 LASTPIN (-4725 3100) $PN 102
J 0
(-4715 3110);
DISPLAY 0.617021 (-4715 3110);
PAINT ORANGE (-4715 3110);
FORCEPROP 2 LASTPIN (-4725 3050) $PN 240
J 0
(-4715 3060);
DISPLAY 0.617021 (-4715 3060);
PAINT ORANGE (-4715 3060);
FORCEPROP 2 LASTPIN (-4725 3000) $PN 95
J 0
(-4715 3010);
DISPLAY 0.617021 (-4715 3010);
PAINT ORANGE (-4715 3010);
FORCEPROP 2 LASTPIN (-4725 2950) $PN 249
J 0
(-4715 2960);
DISPLAY 0.617021 (-4715 2960);
PAINT ORANGE (-4715 2960);
FORCEPROP 2 LASTPIN (-4725 2850) $PN 242
J 0
(-4715 2860);
DISPLAY 0.617021 (-4715 2860);
PAINT ORANGE (-4715 2860);
FORCEPROP 2 LASTPIN (-4725 2800) $PN 97
J 0
(-4715 2810);
DISPLAY 0.617021 (-4715 2810);
PAINT ORANGE (-4715 2810);
FORCEPROP 2 LASTPIN (-4725 2700) $PN 43
J 0
(-4715 2710);
DISPLAY 0.617021 (-4715 2710);
PAINT ORANGE (-4715 2710);
FORCEPROP 2 LASTPIN (-4725 2650) $PN 181
J 0
(-4715 2660);
DISPLAY 0.617021 (-4715 2660);
PAINT ORANGE (-4715 2660);
FORCEPROP 2 LASTPIN (-4725 2600) $PN 36
J 0
(-4715 2610);
DISPLAY 0.617021 (-4715 2610);
PAINT ORANGE (-4715 2610);
FORCEPROP 2 LASTPIN (-4725 2550) $PN 190
J 0
(-4715 2560);
DISPLAY 0.617021 (-4715 2560);
PAINT ORANGE (-4715 2560);
FORCEPROP 2 LASTPIN (-4725 2500) $PN 45
J 0
(-4715 2510);
DISPLAY 0.617021 (-4715 2510);
PAINT ORANGE (-4715 2510);
FORCEPROP 2 LASTPIN (-4725 2450) $PN 183
J 0
(-4715 2460);
DISPLAY 0.617021 (-4715 2460);
PAINT ORANGE (-4715 2460);
FORCEPROP 2 LASTPIN (-4725 2400) $PN 38
J 0
(-4715 2410);
DISPLAY 0.617021 (-4715 2410);
PAINT ORANGE (-4715 2410);
FORCEPROP 2 LASTPIN (-4725 2350) $PN 177
J 0
(-4715 2360);
DISPLAY 0.617021 (-4715 2360);
PAINT ORANGE (-4715 2360);
FORCEPROP 2 LASTPIN (-4725 2300) $PN 32
J 0
(-4715 2310);
DISPLAY 0.617021 (-4715 2310);
PAINT ORANGE (-4715 2310);
FORCEPROP 2 LASTPIN (-4725 2250) $PN 170
J 0
(-4715 2260);
DISPLAY 0.617021 (-4715 2260);
PAINT ORANGE (-4715 2260);
FORCEPROP 2 LASTPIN (-4725 2200) $PN 25
J 0
(-4715 2210);
DISPLAY 0.617021 (-4715 2210);
PAINT ORANGE (-4715 2210);
FORCEPROP 2 LASTPIN (-4725 2150) $PN 179
J 0
(-4715 2160);
DISPLAY 0.617021 (-4715 2160);
PAINT ORANGE (-4715 2160);
FORCEPROP 2 LASTPIN (-4725 2100) $PN 34
J 0
(-4715 2110);
DISPLAY 0.617021 (-4715 2110);
PAINT ORANGE (-4715 2110);
FORCEPROP 2 LASTPIN (-4725 2050) $PN 172
J 0
(-4715 2060);
DISPLAY 0.617021 (-4715 2060);
PAINT ORANGE (-4715 2060);
FORCEPROP 2 LASTPIN (-4725 2000) $PN 27
J 0
(-4715 2010);
DISPLAY 0.617021 (-4715 2010);
PAINT ORANGE (-4715 2010);
FORCEPROP 2 LASTPIN (-4725 1950) $PN 166
J 0
(-4715 1960);
DISPLAY 0.617021 (-4715 1960);
PAINT ORANGE (-4715 1960);
FORCEPROP 2 LASTPIN (-4725 1900) $PN 21
J 0
(-4715 1910);
DISPLAY 0.617021 (-4715 1910);
PAINT ORANGE (-4715 1910);
FORCEPROP 2 LASTPIN (-4725 1850) $PN 159
J 0
(-4715 1860);
DISPLAY 0.617021 (-4715 1860);
PAINT ORANGE (-4715 1860);
FORCEPROP 2 LASTPIN (-4725 1800) $PN 14
J 0
(-4715 1810);
DISPLAY 0.617021 (-4715 1810);
PAINT ORANGE (-4715 1810);
FORCEPROP 2 LASTPIN (-4725 1750) $PN 168
J 0
(-4715 1760);
DISPLAY 0.617021 (-4715 1760);
PAINT ORANGE (-4715 1760);
FORCEPROP 2 LASTPIN (-4725 1700) $PN 23
J 0
(-4715 1710);
DISPLAY 0.617021 (-4715 1710);
PAINT ORANGE (-4715 1710);
FORCEPROP 2 LASTPIN (-4725 1650) $PN 161
J 0
(-4715 1660);
DISPLAY 0.617021 (-4715 1660);
PAINT ORANGE (-4715 1660);
FORCEPROP 2 LASTPIN (-4725 1600) $PN 16
J 0
(-4715 1610);
DISPLAY 0.617021 (-4715 1610);
PAINT ORANGE (-4715 1610);
FORCEPROP 2 LASTPIN (-4725 1550) $PN 155
J 0
(-4715 1560);
DISPLAY 0.617021 (-4715 1560);
PAINT ORANGE (-4715 1560);
FORCEPROP 2 LASTPIN (-4725 1500) $PN 10
J 0
(-4715 1510);
DISPLAY 0.617021 (-4715 1510);
PAINT ORANGE (-4715 1510);
FORCEPROP 2 LASTPIN (-4725 1450) $PN 148
J 0
(-4715 1460);
DISPLAY 0.617021 (-4715 1460);
PAINT ORANGE (-4715 1460);
FORCEPROP 2 LASTPIN (-4725 1400) $PN 3
J 0
(-4715 1410);
DISPLAY 0.617021 (-4715 1410);
PAINT ORANGE (-4715 1410);
FORCEPROP 2 LASTPIN (-4725 1350) $PN 157
J 0
(-4715 1360);
DISPLAY 0.617021 (-4715 1360);
PAINT ORANGE (-4715 1360);
FORCEPROP 2 LASTPIN (-4725 1300) $PN 12
J 0
(-4715 1310);
DISPLAY 0.617021 (-4715 1310);
PAINT ORANGE (-4715 1310);
FORCEPROP 2 LASTPIN (-4725 1250) $PN 150
J 0
(-4715 1260);
DISPLAY 0.617021 (-4715 1260);
PAINT ORANGE (-4715 1260);
FORCEPROP 2 LASTPIN (-4725 1200) $PN 5
J 0
(-4715 1210);
DISPLAY 0.617021 (-4715 1210);
PAINT ORANGE (-4715 1210);
FORCEPROP 2 LASTPIN (-5725 2600) $PN 203
J 2
(-5735 2610);
DISPLAY 0.617021 (-5735 2610);
PAINT ORANGE (-5735 2610);
FORCEPROP 2 LASTPIN (-5725 2550) $PN 60
J 2
(-5735 2560);
DISPLAY 0.617021 (-5735 2560);
PAINT ORANGE (-5735 2560);
FORCEPROP 2 LASTPIN (-5725 3150) $PN 218
J 2
(-5735 3160);
DISPLAY 0.617021 (-5735 3160);
PAINT ORANGE (-5735 3160);
FORCEPROP 2 LASTPIN (-5725 3100) $PN 219
J 2
(-5735 3110);
DISPLAY 0.617021 (-5735 3110);
PAINT ORANGE (-5735 3110);
FORCEPROP 2 LASTPIN (-5725 3050) $PN 74
J 2
(-5735 3060);
DISPLAY 0.617021 (-5735 3060);
PAINT ORANGE (-5735 3060);
FORCEPROP 2 LASTPIN (-5725 3000) $PN 75
J 2
(-5735 3010);
DISPLAY 0.617021 (-5735 3010);
PAINT ORANGE (-5735 3010);
FORCEPROP 2 LASTPIN (-5725 2300) $PN 199
J 2
(-5735 2310);
DISPLAY 0.617021 (-5735 2310);
PAINT ORANGE (-5735 2310);
FORCEPROP 2 LASTPIN (-5725 2250) $PN 54
J 2
(-5735 2260);
DISPLAY 0.617021 (-5735 2260);
PAINT ORANGE (-5735 2260);
FORCEPROP 2 LASTPIN (-5725 2200) $PN 192
J 2
(-5735 2210);
DISPLAY 0.617021 (-5735 2210);
PAINT ORANGE (-5735 2210);
FORCEPROP 2 LASTPIN (-5725 2150) $PN 47
J 2
(-5735 2160);
DISPLAY 0.617021 (-5735 2160);
PAINT ORANGE (-5735 2160);
FORCEPROP 2 LASTPIN (-5725 2100) $PN 201
J 2
(-5735 2110);
DISPLAY 0.617021 (-5735 2110);
PAINT ORANGE (-5735 2110);
FORCEPROP 2 LASTPIN (-5725 2050) $PN 56
J 2
(-5735 2060);
DISPLAY 0.617021 (-5735 2060);
PAINT ORANGE (-5735 2060);
FORCEPROP 2 LASTPIN (-5725 2000) $PN 194
J 2
(-5735 2010);
DISPLAY 0.617021 (-5735 2010);
PAINT ORANGE (-5735 2010);
FORCEPROP 2 LASTPIN (-5725 1950) $PN 49
J 2
(-5735 1960);
DISPLAY 0.617021 (-5735 1960);
PAINT ORANGE (-5735 1960);
FORCEPROP 2 LASTPIN (-5725 2900) $PN 235
J 2
(-5735 2910);
DISPLAY 0.617021 (-5735 2910);
PAINT ORANGE (-5735 2910);
FORCEPROP 2 LASTPIN (-5725 3300) $PN 207
J 2
(-5735 3310);
DISPLAY 0.617021 (-5735 3310);
PAINT ORANGE (-5735 3310);
FORCEPROP 2 LASTPIN (-5725 3250) $PN 63
J 2
(-5735 3260);
DISPLAY 0.617021 (-5735 3260);
PAINT ORANGE (-5735 3260);
FORCEPROP 2 LASTPIN (-5725 3400) $PN 224
J 2
(-5735 3410);
DISPLAY 0.617021 (-5735 3410);
PAINT ORANGE (-5735 3410);
FORCEPROP 2 LASTPIN (-5725 3350) $PN 81
J 2
(-5735 3360);
DISPLAY 0.617021 (-5735 3360);
PAINT ORANGE (-5735 3360);
FORCEPROP 2 LASTPIN (-5725 1700) $PN 208
J 2
(-5735 1710);
DISPLAY 0.617021 (-5735 1710);
PAINT ORANGE (-5735 1710);
FORCEPROP 2 LASTPIN (-5725 1650) $PN 62
J 2
(-5735 1660);
DISPLAY 0.617021 (-5735 1660);
PAINT ORANGE (-5735 1660);
FORCEPROP 2 LASTPIN (-5725 4300) $PN 82
J 2
(-5735 4310);
DISPLAY 0.617021 (-5735 4310);
PAINT ORANGE (-5735 4310);
FORCEPROP 2 LASTPIN (-5725 4250) $PN 86
J 2
(-5735 4260);
DISPLAY 0.617021 (-5735 4260);
PAINT ORANGE (-5735 4260);
FORCEPROP 2 LASTPIN (-5725 4200) $PN 228
J 2
(-5735 4210);
DISPLAY 0.617021 (-5735 4210);
PAINT ORANGE (-5735 4210);
FORCEPROP 2 LASTPIN (-5725 4150) $PN 232
J 2
(-5735 4160);
DISPLAY 0.617021 (-5735 4160);
PAINT ORANGE (-5735 4160);
FORCEPROP 2 LASTPIN (-5725 4100) $PN 65
J 2
(-5735 4110);
DISPLAY 0.617021 (-5735 4110);
PAINT ORANGE (-5735 4110);
FORCEPROP 2 LASTPIN (-5725 4050) $PN 210
J 2
(-5735 4060);
DISPLAY 0.617021 (-5735 4060);
PAINT ORANGE (-5735 4060);
FORCEPROP 2 LASTPIN (-5725 4000) $PN 225
J 2
(-5735 4010);
DISPLAY 0.617021 (-5735 4010);
PAINT ORANGE (-5735 4010);
FORCEPROP 2 LASTPIN (-5725 3950) $PN 66
J 2
(-5735 3960);
DISPLAY 0.617021 (-5735 3960);
PAINT ORANGE (-5735 3960);
FORCEPROP 2 LASTPIN (-5725 3900) $PN 68
J 2
(-5735 3910);
DISPLAY 0.617021 (-5735 3910);
PAINT ORANGE (-5735 3910);
FORCEPROP 2 LASTPIN (-5725 3850) $PN 211
J 2
(-5735 3860);
DISPLAY 0.617021 (-5735 3860);
PAINT ORANGE (-5735 3860);
FORCEPROP 2 LASTPIN (-5725 3800) $PN 69
J 2
(-5735 3810);
DISPLAY 0.617021 (-5735 3810);
PAINT ORANGE (-5735 3810);
FORCEPROP 2 LASTPIN (-5725 3750) $PN 213
J 2
(-5735 3760);
DISPLAY 0.617021 (-5735 3760);
PAINT ORANGE (-5735 3760);
FORCEPROP 2 LASTPIN (-5725 3700) $PN 214
J 2
(-5735 3710);
DISPLAY 0.617021 (-5735 3710);
PAINT ORANGE (-5735 3710);
FORCEPROP 2 LASTPIN (-5725 3650) $PN 71
J 2
(-5735 3660);
DISPLAY 0.617021 (-5735 3660);
PAINT ORANGE (-5735 3660);
FORCEPROP 2 LASTPIN (-5725 3600) $PN 216
J 2
(-5735 3610);
DISPLAY 0.617021 (-5735 3610);
PAINT ORANGE (-5735 3610);
FORCEPROP 2 LASTPIN (-5725 3550) $PN 72
J 2
(-5735 3560);
DISPLAY 0.617021 (-5735 3560);
PAINT ORANGE (-5735 3560);
FORCEPROP 2 LASTPIN (-5725 3500) $PN 79
J 2
(-5735 3510);
DISPLAY 0.617021 (-5735 3510);
PAINT ORANGE (-5735 3510);
FORCEPROP 2 LASTPIN (-4725 3900) $PN 124
J 0
(-4715 3910);
DISPLAY 0.617021 (-4715 3910);
PAINT ORANGE (-4715 3910);
FORCEPROP 2 LASTPIN (-4725 4000) $PN 130
J 0
(-4715 4010);
DISPLAY 0.617021 (-4715 4010);
PAINT ORANGE (-4715 4010);
FORCEPROP 2 LASTPIN (-4725 4100) $PN 137
J 0
(-4715 4110);
DISPLAY 0.617021 (-4715 4110);
PAINT ORANGE (-4715 4110);
FORCEPROP 2 LASTPIN (-4725 3550) $PN 258
J 0
(-4715 3560);
DISPLAY 0.617021 (-4715 3560);
PAINT ORANGE (-4715 3560);
FORCEPROP 2 LASTPIN (-4725 3850) $PN 262
J 0
(-4715 3860);
DISPLAY 0.617021 (-4715 3860);
PAINT ORANGE (-4715 3860);
FORCEPROP 2 LASTPIN (-4725 2750) $PN 188
J 0
(-4715 2760);
DISPLAY 0.617021 (-4715 2760);
PAINT ORANGE (-4715 2760);
FORCEPROP 2 LASTPIN (-4725 4050) $PN 275
J 0
(-4715 4060);
DISPLAY 0.617021 (-4715 4060);
PAINT ORANGE (-4715 4060);
FORCEPROP 2 LASTPIN (-4725 4300) $PN 135
J 0
(-4715 4310);
DISPLAY 0.617021 (-4715 4310);
PAINT ORANGE (-4715 4310);
FORCEPROP 2 LASTPIN (-4725 4350) $PN 280
J 0
(-4715 4360);
DISPLAY 0.617021 (-4715 4360);
PAINT ORANGE (-4715 4360);
FORCEPROP 2 LASTPIN (-4725 2900) $PN 104
J 0
(-4715 2910);
DISPLAY 0.617021 (-4715 2910);
PAINT ORANGE (-4715 2910);
FORCEPROP 1 LAST LOCATION J9U1
J 0
(-5675 4600);
DISPLAY 0.617021 (-5675 4600);
PAINT AQUA (-5675 4600);
FORCEPROP 2 LASTPIN (-4725 4200) $PN 128
J 0
(-4715 4210);
DISPLAY 0.617021 (-4715 4210);
PAINT ORANGE (-4715 4210);
FORCEPROP 0 LAST BOM_SS NOPOP
J 0
(-5378 4536);
DISPLAY 1.021277 (-5378 4536);
PAINT BROWN (-5378 4536);
DISPLAY BOTH (-5378 4536);
FORCEPROP 1 LAST PACK_TYPE PIP
J 0
(-5675 4650);
PAINT SKYBLUE (-5675 4650);
DISPLAY INVISIBLE (-5675 4650);
FORCEPROP 2 LAST BOM_COST MEM
J 0
(-5225 2700);
PAINT ORANGE (-5225 2700);
DISPLAY INVISIBLE (-5225 2700);
FORCEPROP 2 LAST CDS_LIB mstr_sconn
J 0
(-5225 2700);
PAINT ORANGE (-5225 2700);
DISPLAY INVISIBLE (-5225 2700);
FORCEPROP 2 LAST SEC_TYPE PIP
J 0
(-5675 4650);
DISPLAY 1.021277 (-5675 4650);
PAINT ORANGE (-5675 4650);
DISPLAY INVISIBLE (-5675 4650);
FORCEPROP 2 LAST SEC 1
J 0
(-5675 4650);
DISPLAY 0.680851 (-5675 4650);
PAINT MONO (-5675 4650);
DISPLAY INVISIBLE (-5675 4650);
FORCEPROP 2 LAST CDS_LOCATION J9U1
J 0
(-5675 4600);
DISPLAY 0.617021 (-5675 4600);
PAINT AQUA (-5675 4600);
DISPLAY INVISIBLE (-5675 4600);
FORCEPROP 1 LAST PATH I24
J 0
(-5225 4550);
PAINT GREEN (-5225 4550);
DISPLAY INVISIBLE (-5225 4550);
FORCEPROP 2 LAST ROOM DDR4_GH_H
J 0
(-5225 2700);
PAINT ORANGE (-5225 2700);
DISPLAY INVISIBLE (-5225 2700);
FORCEADD TAP..6
(-5975 1950);
FORCEPROP 3 LASTPIN (-5925 1950) SIG_NAME M_H_ECC<0>
J 0
(-5915 1960);
DISPLAY 0.659574 (-5915 1960);
PAINT MONO (-5915 1960);
DISPLAY INVISIBLE (-5915 1960);
FORCEPROP 1 LASTPIN (-5925 1950) BN 0
J 0
(-5975 1960);
DISPLAY 0.617021 (-5975 1960);
PAINT PINK (-5975 1960);
FORCEPROP 2 LAST CDS_LIB mstr_standard
J 0
(-5975 1950);
DISPLAY 0.787234 (-5975 1950);
PAINT MONO (-5975 1950);
DISPLAY INVISIBLE (-5975 1950);
FORCEPROP 1 LAST BODY_TYPE PLUMBING
J 0
(-5975 1900);
DISPLAY 1.234043 (-5975 1900);
PAINT GREEN (-5975 1900);
DISPLAY INVISIBLE (-5975 1900);
FORCEPROP 1 LAST HDL_TAP TRUE
J 0
(-5650 1825);
DISPLAY 1.234043 (-5650 1825);
PAINT GREEN (-5650 1825);
DISPLAY INVISIBLE (-5650 1825);
FORCEPROP 1 LAST PATH I25
J 0
(-5977 1950);
DISPLAY 0.872340 (-5977 1950);
PAINT GREEN (-5977 1950);
DISPLAY INVISIBLE (-5977 1950);
FORCEADD TAP..6
(-5975 2000);
FORCEPROP 3 LASTPIN (-5925 2000) SIG_NAME M_H_ECC<1>
J 0
(-5915 2010);
DISPLAY 0.659574 (-5915 2010);
PAINT MONO (-5915 2010);
DISPLAY INVISIBLE (-5915 2010);
FORCEPROP 1 LASTPIN (-5925 2000) BN 1
J 0
(-5975 2010);
DISPLAY 0.617021 (-5975 2010);
PAINT PINK (-5975 2010);
FORCEPROP 2 LAST CDS_LIB mstr_standard
J 0
(-5975 2000);
DISPLAY 0.787234 (-5975 2000);
PAINT MONO (-5975 2000);
DISPLAY INVISIBLE (-5975 2000);
FORCEPROP 1 LAST BODY_TYPE PLUMBING
J 0
(-5975 1950);
DISPLAY 1.234043 (-5975 1950);
PAINT GREEN (-5975 1950);
DISPLAY INVISIBLE (-5975 1950);
FORCEPROP 1 LAST HDL_TAP TRUE
J 0
(-5650 1875);
DISPLAY 1.234043 (-5650 1875);
PAINT GREEN (-5650 1875);
DISPLAY INVISIBLE (-5650 1875);
FORCEPROP 1 LAST PATH I26
J 0
(-5977 2000);
DISPLAY 0.872340 (-5977 2000);
PAINT GREEN (-5977 2000);
DISPLAY INVISIBLE (-5977 2000);
FORCEADD TAP..6
(-5975 2100);
FORCEPROP 3 LASTPIN (-5925 2100) SIG_NAME M_H_ECC<3>
J 0
(-5915 2110);
DISPLAY 0.659574 (-5915 2110);
PAINT MONO (-5915 2110);
DISPLAY INVISIBLE (-5915 2110);
FORCEPROP 1 LASTPIN (-5925 2100) BN 3
J 0
(-5975 2110);
DISPLAY 0.617021 (-5975 2110);
PAINT PINK (-5975 2110);
FORCEPROP 2 LAST CDS_LIB mstr_standard
J 0
(-5975 2100);
DISPLAY 0.787234 (-5975 2100);
PAINT MONO (-5975 2100);
DISPLAY INVISIBLE (-5975 2100);
FORCEPROP 1 LAST BODY_TYPE PLUMBING
J 0
(-5975 2050);
DISPLAY 1.234043 (-5975 2050);
PAINT GREEN (-5975 2050);
DISPLAY INVISIBLE (-5975 2050);
FORCEPROP 1 LAST HDL_TAP TRUE
J 0
(-5650 1975);
DISPLAY 1.234043 (-5650 1975);
PAINT GREEN (-5650 1975);
DISPLAY INVISIBLE (-5650 1975);
FORCEPROP 1 LAST PATH I27
J 0
(-5977 2100);
DISPLAY 0.872340 (-5977 2100);
PAINT GREEN (-5977 2100);
DISPLAY INVISIBLE (-5977 2100);
FORCEADD TAP..6
(-5975 2050);
FORCEPROP 3 LASTPIN (-5925 2050) SIG_NAME M_H_ECC<2>
J 0
(-5915 2060);
DISPLAY 0.659574 (-5915 2060);
PAINT MONO (-5915 2060);
DISPLAY INVISIBLE (-5915 2060);
FORCEPROP 1 LASTPIN (-5925 2050) BN 2
J 0
(-5975 2060);
DISPLAY 0.617021 (-5975 2060);
PAINT PINK (-5975 2060);
FORCEPROP 2 LAST CDS_LIB mstr_standard
J 0
(-5975 2050);
DISPLAY 0.787234 (-5975 2050);
PAINT MONO (-5975 2050);
DISPLAY INVISIBLE (-5975 2050);
FORCEPROP 1 LAST BODY_TYPE PLUMBING
J 0
(-5975 2000);
DISPLAY 1.234043 (-5975 2000);
PAINT GREEN (-5975 2000);
DISPLAY INVISIBLE (-5975 2000);
FORCEPROP 1 LAST HDL_TAP TRUE
J 0
(-5650 1925);
DISPLAY 1.234043 (-5650 1925);
PAINT GREEN (-5650 1925);
DISPLAY INVISIBLE (-5650 1925);
FORCEPROP 1 LAST PATH I28
J 0
(-5977 2050);
DISPLAY 0.872340 (-5977 2050);
PAINT GREEN (-5977 2050);
DISPLAY INVISIBLE (-5977 2050);
FORCEADD TAP..6
(-5975 2200);
FORCEPROP 3 LASTPIN (-5925 2200) SIG_NAME M_H_ECC<5>
J 0
(-5915 2210);
DISPLAY 0.659574 (-5915 2210);
PAINT MONO (-5915 2210);
DISPLAY INVISIBLE (-5915 2210);
FORCEPROP 1 LASTPIN (-5925 2200) BN 5
J 0
(-5975 2210);
DISPLAY 0.617021 (-5975 2210);
PAINT PINK (-5975 2210);
FORCEPROP 2 LAST CDS_LIB mstr_standard
J 0
(-5975 2200);
DISPLAY 0.787234 (-5975 2200);
PAINT MONO (-5975 2200);
DISPLAY INVISIBLE (-5975 2200);
FORCEPROP 1 LAST BODY_TYPE PLUMBING
J 0
(-5975 2150);
DISPLAY 1.234043 (-5975 2150);
PAINT GREEN (-5975 2150);
DISPLAY INVISIBLE (-5975 2150);
FORCEPROP 1 LAST HDL_TAP TRUE
J 0
(-5650 2075);
DISPLAY 1.234043 (-5650 2075);
PAINT GREEN (-5650 2075);
DISPLAY INVISIBLE (-5650 2075);
FORCEPROP 1 LAST PATH I29
J 0
(-5977 2200);
DISPLAY 0.872340 (-5977 2200);
PAINT GREEN (-5977 2200);
DISPLAY INVISIBLE (-5977 2200);
FORCEADD CAP_A..1
R 2
(-7225 1000);
FORCEPROP 1 LAST LOCATION C1G10
J 2
(-7275 1100);
DISPLAY 0.617021 (-7275 1100);
PAINT AQUA (-7275 1100);
FORCEPROP 1 LAST PART_NUMBER A36096-045
J 2
(-7275 850);
DISPLAY 0.617021 (-7275 850);
PAINT BLUE (-7275 850);
FORCEPROP 1 LAST VALUE 0.01UF
J 2
(-7275 1050);
DISPLAY 0.617021 (-7275 1050);
PAINT SKYBLUE (-7275 1050);
FORCEPROP 1 LAST TOLERANCE 10%
J 2
(-7275 950);
DISPLAY 0.617021 (-7275 950);
PAINT SKYBLUE (-7275 950);
FORCEPROP 1 LAST PACK_TYPE 0402V
J 2
(-7275 800);
DISPLAY 0.617021 (-7275 800);
PAINT SKYBLUE (-7275 800);
FORCEPROP 1 LAST VOLTAGE 25V
J 2
(-7275 1000);
DISPLAY 0.617021 (-7275 1000);
PAINT SKYBLUE (-7275 1000);
FORCEPROP 1 LAST MATERIAL X7R
J 2
(-7275 900);
DISPLAY 0.617021 (-7275 900);
PAINT SKYBLUE (-7275 900);
FORCEPROP 2 LAST CDS_LOCATION C1G10
J 2
(-7275 1100);
DISPLAY 0.617021 (-7275 1100);
PAINT AQUA (-7275 1100);
DISPLAY INVISIBLE (-7275 1100);
FORCEPROP 2 LAST BOM_COST MEM
J 0
(-7225 1000);
PAINT ORANGE (-7225 1000);
DISPLAY INVISIBLE (-7225 1000);
FORCEPROP 2 LAST CDS_LIB dev_discrete
J 0
(-7225 1000);
PAINT ORANGE (-7225 1000);
DISPLAY INVISIBLE (-7225 1000);
FORCEPROP 2 LAST CDS_SEC 1
J 0
(-7275 1200);
PAINT MONO (-7275 1200);
DISPLAY INVISIBLE (-7275 1200);
FORCEPROP 2 LAST $SEC 1
J 0
(-7275 1200);
PAINT MONO (-7275 1200);
DISPLAY INVISIBLE (-7275 1200);
FORCEPROP 1 LAST PATH I3
J 2
(-7275 1150);
DISPLAY 0.978723 (-7275 1150);
PAINT WHITE (-7275 1150);
DISPLAY INVISIBLE (-7275 1150);
FORCEPROP 2 LAST ROOM DDR4_GH_G
J 0
(-7225 1000);
PAINT ORANGE (-7225 1000);
DISPLAY INVISIBLE (-7225 1000);
FORCEPROP 1 LASTPIN (-7225 1100) $PN 1
J 2
(-7235 1080);
DISPLAY 0.787234 (-7235 1080);
PAINT ORANGE (-7235 1080);
DISPLAY INVISIBLE (-7235 1080);
FORCEPROP 1 LASTPIN (-7225 900) $PN 2
J 2
(-7235 880);
DISPLAY 0.787234 (-7235 880);
PAINT ORANGE (-7235 880);
DISPLAY INVISIBLE (-7235 880);
FORCEADD TAP..6
(-5975 2150);
FORCEPROP 3 LASTPIN (-5925 2150) SIG_NAME M_H_ECC<4>
J 0
(-5915 2160);
DISPLAY 0.659574 (-5915 2160);
PAINT MONO (-5915 2160);
DISPLAY INVISIBLE (-5915 2160);
FORCEPROP 1 LASTPIN (-5925 2150) BN 4
J 0
(-5975 2160);
DISPLAY 0.617021 (-5975 2160);
PAINT PINK (-5975 2160);
FORCEPROP 2 LAST CDS_LIB mstr_standard
J 0
(-5975 2150);
DISPLAY 0.787234 (-5975 2150);
PAINT MONO (-5975 2150);
DISPLAY INVISIBLE (-5975 2150);
FORCEPROP 1 LAST BODY_TYPE PLUMBING
J 0
(-5975 2100);
DISPLAY 1.234043 (-5975 2100);
PAINT GREEN (-5975 2100);
DISPLAY INVISIBLE (-5975 2100);
FORCEPROP 1 LAST HDL_TAP TRUE
J 0
(-5650 2025);
DISPLAY 1.234043 (-5650 2025);
PAINT GREEN (-5650 2025);
DISPLAY INVISIBLE (-5650 2025);
FORCEPROP 1 LAST PATH I30
J 0
(-5977 2150);
DISPLAY 0.872340 (-5977 2150);
PAINT GREEN (-5977 2150);
DISPLAY INVISIBLE (-5977 2150);
FORCEADD TAP..6
(-5975 2250);
FORCEPROP 3 LASTPIN (-5925 2250) SIG_NAME M_H_ECC<6>
J 0
(-5915 2260);
DISPLAY 0.659574 (-5915 2260);
PAINT MONO (-5915 2260);
DISPLAY INVISIBLE (-5915 2260);
FORCEPROP 1 LASTPIN (-5925 2250) BN 6
J 0
(-5975 2260);
DISPLAY 0.617021 (-5975 2260);
PAINT PINK (-5975 2260);
FORCEPROP 2 LAST CDS_LIB mstr_standard
J 0
(-5975 2250);
DISPLAY 0.787234 (-5975 2250);
PAINT MONO (-5975 2250);
DISPLAY INVISIBLE (-5975 2250);
FORCEPROP 1 LAST BODY_TYPE PLUMBING
J 0
(-5975 2200);
DISPLAY 1.234043 (-5975 2200);
PAINT GREEN (-5975 2200);
DISPLAY INVISIBLE (-5975 2200);
FORCEPROP 1 LAST HDL_TAP TRUE
J 0
(-5650 2125);
DISPLAY 1.234043 (-5650 2125);
PAINT GREEN (-5650 2125);
DISPLAY INVISIBLE (-5650 2125);
FORCEPROP 1 LAST PATH I31
J 0
(-5977 2250);
DISPLAY 0.872340 (-5977 2250);
PAINT GREEN (-5977 2250);
DISPLAY INVISIBLE (-5977 2250);
FORCEADD TAP..6
(-5975 2300);
FORCEPROP 3 LASTPIN (-5925 2300) SIG_NAME M_H_ECC<7>
J 0
(-5915 2310);
DISPLAY 0.659574 (-5915 2310);
PAINT MONO (-5915 2310);
DISPLAY INVISIBLE (-5915 2310);
FORCEPROP 1 LASTPIN (-5925 2300) BN 7
J 0
(-5975 2310);
DISPLAY 0.617021 (-5975 2310);
PAINT PINK (-5975 2310);
FORCEPROP 2 LAST CDS_LIB mstr_standard
J 0
(-5975 2300);
DISPLAY 0.787234 (-5975 2300);
PAINT MONO (-5975 2300);
DISPLAY INVISIBLE (-5975 2300);
FORCEPROP 1 LAST BODY_TYPE PLUMBING
J 0
(-5975 2250);
DISPLAY 1.234043 (-5975 2250);
PAINT GREEN (-5975 2250);
DISPLAY INVISIBLE (-5975 2250);
FORCEPROP 1 LAST HDL_TAP TRUE
J 0
(-5650 2175);
DISPLAY 1.234043 (-5650 2175);
PAINT GREEN (-5650 2175);
DISPLAY INVISIBLE (-5650 2175);
FORCEPROP 1 LAST PATH I32
J 0
(-5977 2300);
DISPLAY 0.872340 (-5977 2300);
PAINT GREEN (-5977 2300);
DISPLAY INVISIBLE (-5977 2300);
FORCEADD TAP..6
(-5975 2400);
FORCEPROP 3 LASTPIN (-5925 2400) SIG_NAME M_H_ODT<2>
J 0
(-5915 2410);
DISPLAY 0.659574 (-5915 2410);
PAINT MONO (-5915 2410);
DISPLAY INVISIBLE (-5915 2410);
FORCEPROP 1 LASTPIN (-5925 2400) BN 2
J 0
(-5975 2410);
DISPLAY 0.617021 (-5975 2410);
PAINT PINK (-5975 2410);
FORCEPROP 2 LAST CDS_LIB mstr_standard
J 0
(-5975 2400);
DISPLAY 0.787234 (-5975 2400);
PAINT MONO (-5975 2400);
DISPLAY INVISIBLE (-5975 2400);
FORCEPROP 1 LAST BODY_TYPE PLUMBING
J 0
(-5975 2350);
DISPLAY 1.234043 (-5975 2350);
PAINT GREEN (-5975 2350);
DISPLAY INVISIBLE (-5975 2350);
FORCEPROP 1 LAST HDL_TAP TRUE
J 0
(-5650 2275);
DISPLAY 1.234043 (-5650 2275);
PAINT GREEN (-5650 2275);
DISPLAY INVISIBLE (-5650 2275);
FORCEPROP 1 LAST PATH I33
J 0
(-5977 2400);
DISPLAY 0.872340 (-5977 2400);
PAINT GREEN (-5977 2400);
DISPLAY INVISIBLE (-5977 2400);
FORCEADD TAP..6
(-5975 2450);
FORCEPROP 3 LASTPIN (-5925 2450) SIG_NAME M_H_ODT<3>
J 0
(-5915 2460);
DISPLAY 0.659574 (-5915 2460);
PAINT MONO (-5915 2460);
DISPLAY INVISIBLE (-5915 2460);
FORCEPROP 1 LASTPIN (-5925 2450) BN 3
J 0
(-5975 2460);
DISPLAY 0.617021 (-5975 2460);
PAINT PINK (-5975 2460);
FORCEPROP 2 LAST CDS_LIB mstr_standard
J 0
(-5975 2450);
DISPLAY 0.787234 (-5975 2450);
PAINT MONO (-5975 2450);
DISPLAY INVISIBLE (-5975 2450);
FORCEPROP 1 LAST BODY_TYPE PLUMBING
J 0
(-5975 2400);
DISPLAY 1.234043 (-5975 2400);
PAINT GREEN (-5975 2400);
DISPLAY INVISIBLE (-5975 2400);
FORCEPROP 1 LAST HDL_TAP TRUE
J 0
(-5650 2325);
DISPLAY 1.234043 (-5650 2325);
PAINT GREEN (-5650 2325);
DISPLAY INVISIBLE (-5650 2325);
FORCEPROP 1 LAST PATH I34
J 0
(-5977 2450);
DISPLAY 0.872340 (-5977 2450);
PAINT GREEN (-5977 2450);
DISPLAY INVISIBLE (-5977 2450);
FORCEADD TAP..6
(-6175 3000);
FORCEPROP 3 LASTPIN (-6125 3000) SIG_NAME M_H_CLK_DN<2>
J 0
(-6115 3010);
DISPLAY 0.659574 (-6115 3010);
PAINT MONO (-6115 3010);
DISPLAY INVISIBLE (-6115 3010);
FORCEPROP 1 LASTPIN (-6125 3000) BN 2
J 0
(-6175 3010);
DISPLAY 0.617021 (-6175 3010);
PAINT PINK (-6175 3010);
FORCEPROP 2 LAST CDS_LIB mstr_standard
J 0
(-6175 3000);
DISPLAY 0.787234 (-6175 3000);
PAINT MONO (-6175 3000);
DISPLAY INVISIBLE (-6175 3000);
FORCEPROP 1 LAST BODY_TYPE PLUMBING
J 0
(-6175 2950);
DISPLAY 1.234043 (-6175 2950);
PAINT GREEN (-6175 2950);
DISPLAY INVISIBLE (-6175 2950);
FORCEPROP 1 LAST HDL_TAP TRUE
J 0
(-5850 2875);
DISPLAY 1.234043 (-5850 2875);
PAINT GREEN (-5850 2875);
DISPLAY INVISIBLE (-5850 2875);
FORCEPROP 1 LAST PATH I35
J 0
(-6177 3000);
DISPLAY 0.872340 (-6177 3000);
PAINT GREEN (-6177 3000);
DISPLAY INVISIBLE (-6177 3000);
FORCEADD TAP..6
(-6175 3100);
FORCEPROP 3 LASTPIN (-6125 3100) SIG_NAME M_H_CLK_DN<3>
J 0
(-6115 3110);
DISPLAY 0.659574 (-6115 3110);
PAINT MONO (-6115 3110);
DISPLAY INVISIBLE (-6115 3110);
FORCEPROP 1 LASTPIN (-6125 3100) BN 3
J 0
(-6175 3110);
DISPLAY 0.617021 (-6175 3110);
PAINT PINK (-6175 3110);
FORCEPROP 2 LAST CDS_LIB mstr_standard
J 0
(-6175 3100);
DISPLAY 0.787234 (-6175 3100);
PAINT MONO (-6175 3100);
DISPLAY INVISIBLE (-6175 3100);
FORCEPROP 1 LAST BODY_TYPE PLUMBING
J 0
(-6175 3050);
DISPLAY 1.234043 (-6175 3050);
PAINT GREEN (-6175 3050);
DISPLAY INVISIBLE (-6175 3050);
FORCEPROP 1 LAST HDL_TAP TRUE
J 0
(-5850 2975);
DISPLAY 1.234043 (-5850 2975);
PAINT GREEN (-5850 2975);
DISPLAY INVISIBLE (-5850 2975);
FORCEPROP 1 LAST PATH I36
J 0
(-6177 3100);
DISPLAY 0.872340 (-6177 3100);
PAINT GREEN (-6177 3100);
DISPLAY INVISIBLE (-6177 3100);
FORCEADD TAP..6
(-5975 2600);
FORCEPROP 3 LASTPIN (-5925 2600) SIG_NAME M_H_CKE<3>
J 0
(-5915 2610);
DISPLAY 0.659574 (-5915 2610);
PAINT MONO (-5915 2610);
DISPLAY INVISIBLE (-5915 2610);
FORCEPROP 1 LASTPIN (-5925 2600) BN 3
J 0
(-5975 2610);
DISPLAY 0.617021 (-5975 2610);
PAINT PINK (-5975 2610);
FORCEPROP 2 LAST CDS_LIB mstr_standard
J 0
(-5975 2600);
DISPLAY 0.787234 (-5975 2600);
PAINT MONO (-5975 2600);
DISPLAY INVISIBLE (-5975 2600);
FORCEPROP 1 LAST BODY_TYPE PLUMBING
J 0
(-5975 2550);
DISPLAY 1.234043 (-5975 2550);
PAINT GREEN (-5975 2550);
DISPLAY INVISIBLE (-5975 2550);
FORCEPROP 1 LAST HDL_TAP TRUE
J 0
(-5650 2475);
DISPLAY 1.234043 (-5650 2475);
PAINT GREEN (-5650 2475);
DISPLAY INVISIBLE (-5650 2475);
FORCEPROP 1 LAST PATH I37
J 0
(-5977 2600);
DISPLAY 0.872340 (-5977 2600);
PAINT GREEN (-5977 2600);
DISPLAY INVISIBLE (-5977 2600);
FORCEADD TAP..6
(-5975 2550);
FORCEPROP 3 LASTPIN (-5925 2550) SIG_NAME M_H_CKE<2>
J 0
(-5915 2560);
DISPLAY 0.659574 (-5915 2560);
PAINT MONO (-5915 2560);
DISPLAY INVISIBLE (-5915 2560);
FORCEPROP 1 LASTPIN (-5925 2550) BN 2
J 0
(-5975 2560);
DISPLAY 0.617021 (-5975 2560);
PAINT PINK (-5975 2560);
FORCEPROP 2 LAST CDS_LIB mstr_standard
J 0
(-5975 2550);
DISPLAY 0.787234 (-5975 2550);
PAINT MONO (-5975 2550);
DISPLAY INVISIBLE (-5975 2550);
FORCEPROP 1 LAST BODY_TYPE PLUMBING
J 0
(-5975 2500);
DISPLAY 1.234043 (-5975 2500);
PAINT GREEN (-5975 2500);
DISPLAY INVISIBLE (-5975 2500);
FORCEPROP 1 LAST HDL_TAP TRUE
J 0
(-5650 2425);
DISPLAY 1.234043 (-5650 2425);
PAINT GREEN (-5650 2425);
DISPLAY INVISIBLE (-5650 2425);
FORCEPROP 1 LAST PATH I38
J 0
(-5977 2550);
DISPLAY 0.872340 (-5977 2550);
PAINT GREEN (-5977 2550);
DISPLAY INVISIBLE (-5977 2550);
FORCEADD TAP..6
(-5975 2750);
FORCEPROP 3 LASTPIN (-5925 2750) SIG_NAME M_H_CS_N<5>
J 0
(-5915 2760);
DISPLAY 0.659574 (-5915 2760);
PAINT MONO (-5915 2760);
DISPLAY INVISIBLE (-5915 2760);
FORCEPROP 1 LASTPIN (-5925 2750) BN 5
J 0
(-5975 2760);
DISPLAY 0.617021 (-5975 2760);
PAINT PINK (-5975 2760);
FORCEPROP 2 LAST CDS_LIB mstr_standard
J 0
(-5975 2750);
DISPLAY 0.787234 (-5975 2750);
PAINT MONO (-5975 2750);
DISPLAY INVISIBLE (-5975 2750);
FORCEPROP 1 LAST BODY_TYPE PLUMBING
J 0
(-5975 2700);
DISPLAY 1.234043 (-5975 2700);
PAINT GREEN (-5975 2700);
DISPLAY INVISIBLE (-5975 2700);
FORCEPROP 1 LAST HDL_TAP TRUE
J 0
(-5650 2625);
DISPLAY 1.234043 (-5650 2625);
PAINT GREEN (-5650 2625);
DISPLAY INVISIBLE (-5650 2625);
FORCEPROP 1 LAST PATH I39
J 0
(-5977 2750);
DISPLAY 0.872340 (-5977 2750);
PAINT GREEN (-5977 2750);
DISPLAY INVISIBLE (-5977 2750);
FORCEADD GND..1
(-7225 750);
FORCEPROP 3 LASTPIN (-7225 800) SIG_NAME GND\g
J 0
(-7215 810);
DISPLAY 0.659574 (-7215 810);
PAINT MONO (-7215 810);
DISPLAY INVISIBLE (-7215 810);
FORCEPROP 1 LAST VOLTAGE 0
J 0
(-7225 750);
PAINT SKYBLUE (-7225 750);
DISPLAY INVISIBLE (-7225 750);
FORCEPROP 2 LAST BOM_COST MEM
J 0
(-7225 755);
PAINT ORANGE (-7225 755);
DISPLAY INVISIBLE (-7225 755);
FORCEPROP 1 LAST SIZE 1B
J 0
(-7150 700);
DISPLAY 1.787234 (-7150 700);
PAINT GREEN (-7150 700);
DISPLAY INVISIBLE (-7150 700);
FORCEPROP 2 LAST CDS_LIB mstr_symbols
J 0
(-7225 750);
PAINT ORANGE (-7225 750);
DISPLAY INVISIBLE (-7225 750);
FORCEPROP 1 LAST BODY_TYPE PLUMBING
J 0
(-7270 707);
DISPLAY 0.340426 (-7270 707);
PAINT GREEN (-7270 707);
DISPLAY INVISIBLE (-7270 707);
FORCEPROP 1 LAST PATH I4
J 0
(-7150 750);
DISPLAY 0.872340 (-7150 750);
PAINT AQUA (-7150 750);
DISPLAY INVISIBLE (-7150 750);
FORCEPROP 2 LAST ROOM DDR4_GH_G
J 0
(-7225 755);
PAINT ORANGE (-7225 755);
DISPLAY INVISIBLE (-7225 755);
FORCEPROP 1 LAST HDL_POWER GND
J 0
(-7225 900);
DISPLAY 1.404255 (-7225 900);
PAINT GREEN (-7225 900);
DISPLAY INVISIBLE (-7225 900);
FORCEADD TAP..6
(-5975 2700);
FORCEPROP 3 LASTPIN (-5925 2700) SIG_NAME M_H_CS_N<4>
J 0
(-5915 2710);
DISPLAY 0.659574 (-5915 2710);
PAINT MONO (-5915 2710);
DISPLAY INVISIBLE (-5915 2710);
FORCEPROP 1 LASTPIN (-5925 2700) BN 4
J 0
(-5975 2710);
DISPLAY 0.617021 (-5975 2710);
PAINT PINK (-5975 2710);
FORCEPROP 2 LAST CDS_LIB mstr_standard
J 0
(-5975 2700);
DISPLAY 0.787234 (-5975 2700);
PAINT MONO (-5975 2700);
DISPLAY INVISIBLE (-5975 2700);
FORCEPROP 1 LAST BODY_TYPE PLUMBING
J 0
(-5975 2650);
DISPLAY 1.234043 (-5975 2650);
PAINT GREEN (-5975 2650);
DISPLAY INVISIBLE (-5975 2650);
FORCEPROP 1 LAST HDL_TAP TRUE
J 0
(-5650 2575);
DISPLAY 1.234043 (-5650 2575);
PAINT GREEN (-5650 2575);
DISPLAY INVISIBLE (-5650 2575);
FORCEPROP 1 LAST PATH I40
J 0
(-5977 2700);
DISPLAY 0.872340 (-5977 2700);
PAINT GREEN (-5977 2700);
DISPLAY INVISIBLE (-5977 2700);
FORCEADD TAP..6
(-5975 2850);
FORCEPROP 3 LASTPIN (-5925 2850) SIG_NAME M_H_CS_N<7>
J 0
(-5915 2860);
DISPLAY 0.659574 (-5915 2860);
PAINT MONO (-5915 2860);
DISPLAY INVISIBLE (-5915 2860);
FORCEPROP 1 LASTPIN (-5925 2850) BN 7
J 0
(-5975 2860);
DISPLAY 0.617021 (-5975 2860);
PAINT PINK (-5975 2860);
FORCEPROP 2 LAST CDS_LIB mstr_standard
J 0
(-5975 2850);
DISPLAY 0.787234 (-5975 2850);
PAINT MONO (-5975 2850);
DISPLAY INVISIBLE (-5975 2850);
FORCEPROP 1 LAST BODY_TYPE PLUMBING
J 0
(-5975 2800);
DISPLAY 1.234043 (-5975 2800);
PAINT GREEN (-5975 2800);
DISPLAY INVISIBLE (-5975 2800);
FORCEPROP 1 LAST HDL_TAP TRUE
J 0
(-5650 2725);
DISPLAY 1.234043 (-5650 2725);
PAINT GREEN (-5650 2725);
DISPLAY INVISIBLE (-5650 2725);
FORCEPROP 1 LAST PATH I41
J 0
(-5977 2850);
DISPLAY 0.872340 (-5977 2850);
PAINT GREEN (-5977 2850);
DISPLAY INVISIBLE (-5977 2850);
FORCEADD TAP..6
(-5975 2800);
FORCEPROP 3 LASTPIN (-5925 2800) SIG_NAME M_H_CS_N<6>
J 0
(-5915 2810);
DISPLAY 0.659574 (-5915 2810);
PAINT MONO (-5915 2810);
DISPLAY INVISIBLE (-5915 2810);
FORCEPROP 1 LASTPIN (-5925 2800) BN 6
J 0
(-5975 2810);
DISPLAY 0.617021 (-5975 2810);
PAINT PINK (-5975 2810);
FORCEPROP 2 LAST CDS_LIB mstr_standard
J 0
(-5975 2800);
DISPLAY 0.787234 (-5975 2800);
PAINT MONO (-5975 2800);
DISPLAY INVISIBLE (-5975 2800);
FORCEPROP 1 LAST BODY_TYPE PLUMBING
J 0
(-5975 2750);
DISPLAY 1.234043 (-5975 2750);
PAINT GREEN (-5975 2750);
DISPLAY INVISIBLE (-5975 2750);
FORCEPROP 1 LAST HDL_TAP TRUE
J 0
(-5650 2675);
DISPLAY 1.234043 (-5650 2675);
PAINT GREEN (-5650 2675);
DISPLAY INVISIBLE (-5650 2675);
FORCEPROP 1 LAST PATH I42
J 0
(-5977 2800);
DISPLAY 0.872340 (-5977 2800);
PAINT GREEN (-5977 2800);
DISPLAY INVISIBLE (-5977 2800);
FORCEADD TAP..6
(-5975 3150);
FORCEPROP 3 LASTPIN (-5925 3150) SIG_NAME M_H_CLK_DP<3>
J 0
(-5915 3160);
DISPLAY 0.659574 (-5915 3160);
PAINT MONO (-5915 3160);
DISPLAY INVISIBLE (-5915 3160);
FORCEPROP 1 LASTPIN (-5925 3150) BN 3
J 0
(-5975 3160);
DISPLAY 0.617021 (-5975 3160);
PAINT PINK (-5975 3160);
FORCEPROP 2 LAST CDS_LIB mstr_standard
J 0
(-5975 3150);
DISPLAY 0.787234 (-5975 3150);
PAINT MONO (-5975 3150);
DISPLAY INVISIBLE (-5975 3150);
FORCEPROP 1 LAST BODY_TYPE PLUMBING
J 0
(-5975 3100);
DISPLAY 1.234043 (-5975 3100);
PAINT GREEN (-5975 3100);
DISPLAY INVISIBLE (-5975 3100);
FORCEPROP 1 LAST HDL_TAP TRUE
J 0
(-5650 3025);
DISPLAY 1.234043 (-5650 3025);
PAINT GREEN (-5650 3025);
DISPLAY INVISIBLE (-5650 3025);
FORCEPROP 1 LAST PATH I43
J 0
(-5977 3150);
DISPLAY 0.872340 (-5977 3150);
PAINT GREEN (-5977 3150);
DISPLAY INVISIBLE (-5977 3150);
FORCEADD TAP..6
(-5975 3050);
FORCEPROP 3 LASTPIN (-5925 3050) SIG_NAME M_H_CLK_DP<2>
J 0
(-5915 3060);
DISPLAY 0.659574 (-5915 3060);
PAINT MONO (-5915 3060);
DISPLAY INVISIBLE (-5915 3060);
FORCEPROP 1 LASTPIN (-5925 3050) BN 2
J 0
(-5975 3060);
DISPLAY 0.617021 (-5975 3060);
PAINT PINK (-5975 3060);
FORCEPROP 2 LAST CDS_LIB mstr_standard
J 0
(-5975 3050);
DISPLAY 0.787234 (-5975 3050);
PAINT MONO (-5975 3050);
DISPLAY INVISIBLE (-5975 3050);
FORCEPROP 1 LAST BODY_TYPE PLUMBING
J 0
(-5975 3000);
DISPLAY 1.234043 (-5975 3000);
PAINT GREEN (-5975 3000);
DISPLAY INVISIBLE (-5975 3000);
FORCEPROP 1 LAST HDL_TAP TRUE
J 0
(-5650 2925);
DISPLAY 1.234043 (-5650 2925);
PAINT GREEN (-5650 2925);
DISPLAY INVISIBLE (-5650 2925);
FORCEPROP 1 LAST PATH I44
J 0
(-5977 3050);
DISPLAY 0.872340 (-5977 3050);
PAINT GREEN (-5977 3050);
DISPLAY INVISIBLE (-5977 3050);
FORCEADD TAP..6
(-5975 3250);
FORCEPROP 3 LASTPIN (-5925 3250) SIG_NAME M_H_BG<0>
J 0
(-5915 3260);
DISPLAY 0.659574 (-5915 3260);
PAINT MONO (-5915 3260);
DISPLAY INVISIBLE (-5915 3260);
FORCEPROP 1 LASTPIN (-5925 3250) BN 0
J 0
(-5975 3260);
DISPLAY 0.617021 (-5975 3260);
PAINT PINK (-5975 3260);
FORCEPROP 2 LAST CDS_LIB mstr_standard
J 0
(-5975 3250);
DISPLAY 0.787234 (-5975 3250);
PAINT MONO (-5975 3250);
DISPLAY INVISIBLE (-5975 3250);
FORCEPROP 1 LAST BODY_TYPE PLUMBING
J 0
(-5975 3200);
DISPLAY 1.234043 (-5975 3200);
PAINT GREEN (-5975 3200);
DISPLAY INVISIBLE (-5975 3200);
FORCEPROP 1 LAST HDL_TAP TRUE
J 0
(-5650 3125);
DISPLAY 1.234043 (-5650 3125);
PAINT GREEN (-5650 3125);
DISPLAY INVISIBLE (-5650 3125);
FORCEPROP 1 LAST PATH I45
J 0
(-5977 3250);
DISPLAY 0.872340 (-5977 3250);
PAINT GREEN (-5977 3250);
DISPLAY INVISIBLE (-5977 3250);
FORCEADD TAP..6
(-5975 3350);
FORCEPROP 3 LASTPIN (-5925 3350) SIG_NAME M_H_BA<0>
J 0
(-5915 3360);
DISPLAY 0.659574 (-5915 3360);
PAINT MONO (-5915 3360);
DISPLAY INVISIBLE (-5915 3360);
FORCEPROP 1 LASTPIN (-5925 3350) BN 0
J 0
(-5975 3360);
DISPLAY 0.617021 (-5975 3360);
PAINT PINK (-5975 3360);
FORCEPROP 2 LAST CDS_LIB mstr_standard
J 0
(-5975 3350);
DISPLAY 0.787234 (-5975 3350);
PAINT MONO (-5975 3350);
DISPLAY INVISIBLE (-5975 3350);
FORCEPROP 1 LAST BODY_TYPE PLUMBING
J 0
(-5975 3300);
DISPLAY 1.234043 (-5975 3300);
PAINT GREEN (-5975 3300);
DISPLAY INVISIBLE (-5975 3300);
FORCEPROP 1 LAST HDL_TAP TRUE
J 0
(-5650 3225);
DISPLAY 1.234043 (-5650 3225);
PAINT GREEN (-5650 3225);
DISPLAY INVISIBLE (-5650 3225);
FORCEPROP 1 LAST PATH I46
J 0
(-5977 3350);
DISPLAY 0.872340 (-5977 3350);
PAINT GREEN (-5977 3350);
DISPLAY INVISIBLE (-5977 3350);
FORCEADD TAP..6
(-5975 3300);
FORCEPROP 3 LASTPIN (-5925 3300) SIG_NAME M_H_BG<1>
J 0
(-5915 3310);
DISPLAY 0.659574 (-5915 3310);
PAINT MONO (-5915 3310);
DISPLAY INVISIBLE (-5915 3310);
FORCEPROP 1 LASTPIN (-5925 3300) BN 1
J 0
(-5975 3310);
DISPLAY 0.617021 (-5975 3310);
PAINT PINK (-5975 3310);
FORCEPROP 2 LAST CDS_LIB mstr_standard
J 0
(-5975 3300);
DISPLAY 0.787234 (-5975 3300);
PAINT MONO (-5975 3300);
DISPLAY INVISIBLE (-5975 3300);
FORCEPROP 1 LAST BODY_TYPE PLUMBING
J 0
(-5975 3250);
DISPLAY 1.234043 (-5975 3250);
PAINT GREEN (-5975 3250);
DISPLAY INVISIBLE (-5975 3250);
FORCEPROP 1 LAST HDL_TAP TRUE
J 0
(-5650 3175);
DISPLAY 1.234043 (-5650 3175);
PAINT GREEN (-5650 3175);
DISPLAY INVISIBLE (-5650 3175);
FORCEPROP 1 LAST PATH I47
J 0
(-5977 3300);
DISPLAY 0.872340 (-5977 3300);
PAINT GREEN (-5977 3300);
DISPLAY INVISIBLE (-5977 3300);
FORCEADD TAP..6
(-5975 3400);
FORCEPROP 3 LASTPIN (-5925 3400) SIG_NAME M_H_BA<1>
J 0
(-5915 3410);
DISPLAY 0.659574 (-5915 3410);
PAINT MONO (-5915 3410);
DISPLAY INVISIBLE (-5915 3410);
FORCEPROP 1 LASTPIN (-5925 3400) BN 1
J 0
(-5975 3410);
DISPLAY 0.617021 (-5975 3410);
PAINT PINK (-5975 3410);
FORCEPROP 2 LAST CDS_LIB mstr_standard
J 0
(-5975 3400);
DISPLAY 0.787234 (-5975 3400);
PAINT MONO (-5975 3400);
DISPLAY INVISIBLE (-5975 3400);
FORCEPROP 1 LAST BODY_TYPE PLUMBING
J 0
(-5975 3350);
DISPLAY 1.234043 (-5975 3350);
PAINT GREEN (-5975 3350);
DISPLAY INVISIBLE (-5975 3350);
FORCEPROP 1 LAST HDL_TAP TRUE
J 0
(-5650 3275);
DISPLAY 1.234043 (-5650 3275);
PAINT GREEN (-5650 3275);
DISPLAY INVISIBLE (-5650 3275);
FORCEPROP 1 LAST PATH I48
J 0
(-5977 3400);
DISPLAY 0.872340 (-5977 3400);
PAINT GREEN (-5977 3400);
DISPLAY INVISIBLE (-5977 3400);
FORCEADD TAP..6
(-5975 3500);
FORCEPROP 3 LASTPIN (-5925 3500) SIG_NAME M_H_MA<0>
J 0
(-5915 3510);
DISPLAY 0.659574 (-5915 3510);
PAINT MONO (-5915 3510);
DISPLAY INVISIBLE (-5915 3510);
FORCEPROP 1 LASTPIN (-5925 3500) BN 0
J 0
(-5975 3510);
DISPLAY 0.617021 (-5975 3510);
PAINT PINK (-5975 3510);
FORCEPROP 2 LAST CDS_LIB mstr_standard
J 2
(-5975 3500);
DISPLAY 0.787234 (-5975 3500);
PAINT MONO (-5975 3500);
DISPLAY INVISIBLE (-5975 3500);
FORCEPROP 1 LAST BODY_TYPE PLUMBING
J 0
(-5975 3450);
DISPLAY 1.234043 (-5975 3450);
PAINT GREEN (-5975 3450);
DISPLAY INVISIBLE (-5975 3450);
FORCEPROP 1 LAST HDL_TAP TRUE
J 0
(-5650 3375);
DISPLAY 1.234043 (-5650 3375);
PAINT GREEN (-5650 3375);
DISPLAY INVISIBLE (-5650 3375);
FORCEPROP 1 LAST PATH I49
J 0
(-5977 3500);
DISPLAY 0.872340 (-5977 3500);
PAINT GREEN (-5977 3500);
DISPLAY INVISIBLE (-5977 3500);
FORCEADD OFFPAGE..1
(-6625 900);
FORCEPROP 2 LAST $XR5 82 
J 0
(-6846 864);
DISPLAY 0.638298 (-6846 864);
PAINT MONO (-6846 864);
FORCEPROP 2 LAST $XR4 81 
J 0
(-7206 900);
DISPLAY 0.638298 (-7206 900);
PAINT MONO (-7206 900);
FORCEPROP 2 LAST $XR3 79 
J 0
(-7116 900);
DISPLAY 0.638298 (-7116 900);
PAINT MONO (-7116 900);
FORCEPROP 2 LAST $XR2 78 
J 0
(-7026 900);
DISPLAY 0.638298 (-7026 900);
PAINT MONO (-7026 900);
FORCEPROP 2 LAST $XR1 77 
J 0
(-6936 900);
DISPLAY 0.638298 (-6936 900);
PAINT MONO (-6936 900);
FORCEPROP 2 LAST $XR0 89 
J 0
(-6846 900);
DISPLAY 0.638298 (-6846 900);
PAINT MONO (-6846 900);
FORCEPROP 2 LAST CDS_LIB mstr_standard
J 0
(-6625 900);
PAINT ORANGE (-6625 900);
DISPLAY INVISIBLE (-6625 900);
FORCEPROP 1 LAST OFFPAGE TRUE
J 0
(-6300 775);
DISPLAY 0.936170 (-6300 775);
PAINT GREEN (-6300 775);
DISPLAY INVISIBLE (-6300 775);
FORCEPROP 1 LAST COMMENT_BODY TRUE
J 0
(-6500 800);
DISPLAY 0.936170 (-6500 800);
PAINT GREEN (-6500 800);
DISPLAY INVISIBLE (-6500 800);
FORCEPROP 2 LAST PATH I5
J 0
(-6900 950);
DISPLAY 1.021277 (-6900 950);
PAINT ORANGE (-6900 950);
DISPLAY INVISIBLE (-6900 950);
FORCEADD TAP..6
R 2
(-4475 1200);
FORCEPROP 3 LASTPIN (-4525 1200) SIG_NAME M_H_DQ<0>
J 0
(-4515 1210);
DISPLAY 0.659574 (-4515 1210);
PAINT MONO (-4515 1210);
DISPLAY INVISIBLE (-4515 1210);
FORCEPROP 1 LASTPIN (-4525 1200) BN 0
J 2
(-4475 1210);
DISPLAY 0.617021 (-4475 1210);
PAINT PINK (-4475 1210);
FORCEPROP 2 LAST CDS_LIB mstr_standard
J 2
(-4475 1200);
DISPLAY 0.787234 (-4475 1200);
PAINT MONO (-4475 1200);
DISPLAY INVISIBLE (-4475 1200);
FORCEPROP 1 LAST BODY_TYPE PLUMBING
J 2
(-4475 1150);
DISPLAY 1.234043 (-4475 1150);
PAINT GREEN (-4475 1150);
DISPLAY INVISIBLE (-4475 1150);
FORCEPROP 1 LAST HDL_TAP TRUE
J 2
(-4800 1075);
DISPLAY 1.234043 (-4800 1075);
PAINT GREEN (-4800 1075);
DISPLAY INVISIBLE (-4800 1075);
FORCEPROP 1 LAST PATH I50
J 2
(-4473 1200);
DISPLAY 0.872340 (-4473 1200);
PAINT GREEN (-4473 1200);
DISPLAY INVISIBLE (-4473 1200);
FORCEADD TAP..6
R 2
(-4475 1350);
FORCEPROP 3 LASTPIN (-4525 1350) SIG_NAME M_H_DQ<3>
J 0
(-4515 1360);
DISPLAY 0.659574 (-4515 1360);
PAINT MONO (-4515 1360);
DISPLAY INVISIBLE (-4515 1360);
FORCEPROP 1 LASTPIN (-4525 1350) BN 3
J 2
(-4475 1360);
DISPLAY 0.617021 (-4475 1360);
PAINT PINK (-4475 1360);
FORCEPROP 2 LAST CDS_LIB mstr_standard
J 2
(-4475 1350);
DISPLAY 0.787234 (-4475 1350);
PAINT MONO (-4475 1350);
DISPLAY INVISIBLE (-4475 1350);
FORCEPROP 1 LAST BODY_TYPE PLUMBING
J 2
(-4475 1300);
DISPLAY 1.234043 (-4475 1300);
PAINT GREEN (-4475 1300);
DISPLAY INVISIBLE (-4475 1300);
FORCEPROP 1 LAST HDL_TAP TRUE
J 2
(-4800 1225);
DISPLAY 1.234043 (-4800 1225);
PAINT GREEN (-4800 1225);
DISPLAY INVISIBLE (-4800 1225);
FORCEPROP 1 LAST PATH I51
J 2
(-4473 1350);
DISPLAY 0.872340 (-4473 1350);
PAINT GREEN (-4473 1350);
DISPLAY INVISIBLE (-4473 1350);
FORCEADD TAP..6
R 2
(-4475 1250);
FORCEPROP 3 LASTPIN (-4525 1250) SIG_NAME M_H_DQ<1>
J 0
(-4515 1260);
DISPLAY 0.659574 (-4515 1260);
PAINT MONO (-4515 1260);
DISPLAY INVISIBLE (-4515 1260);
FORCEPROP 1 LASTPIN (-4525 1250) BN 1
J 2
(-4475 1260);
DISPLAY 0.617021 (-4475 1260);
PAINT PINK (-4475 1260);
FORCEPROP 2 LAST CDS_LIB mstr_standard
J 2
(-4475 1250);
DISPLAY 0.787234 (-4475 1250);
PAINT MONO (-4475 1250);
DISPLAY INVISIBLE (-4475 1250);
FORCEPROP 1 LAST BODY_TYPE PLUMBING
J 2
(-4475 1200);
DISPLAY 1.234043 (-4475 1200);
PAINT GREEN (-4475 1200);
DISPLAY INVISIBLE (-4475 1200);
FORCEPROP 1 LAST HDL_TAP TRUE
J 2
(-4800 1125);
DISPLAY 1.234043 (-4800 1125);
PAINT GREEN (-4800 1125);
DISPLAY INVISIBLE (-4800 1125);
FORCEPROP 1 LAST PATH I52
J 2
(-4473 1250);
DISPLAY 0.872340 (-4473 1250);
PAINT GREEN (-4473 1250);
DISPLAY INVISIBLE (-4473 1250);
FORCEADD TAP..6
R 2
(-4475 1300);
FORCEPROP 3 LASTPIN (-4525 1300) SIG_NAME M_H_DQ<2>
J 0
(-4515 1310);
DISPLAY 0.659574 (-4515 1310);
PAINT MONO (-4515 1310);
DISPLAY INVISIBLE (-4515 1310);
FORCEPROP 1 LASTPIN (-4525 1300) BN 2
J 2
(-4475 1310);
DISPLAY 0.617021 (-4475 1310);
PAINT PINK (-4475 1310);
FORCEPROP 2 LAST CDS_LIB mstr_standard
J 2
(-4475 1300);
DISPLAY 0.787234 (-4475 1300);
PAINT MONO (-4475 1300);
DISPLAY INVISIBLE (-4475 1300);
FORCEPROP 1 LAST BODY_TYPE PLUMBING
J 2
(-4475 1250);
DISPLAY 1.234043 (-4475 1250);
PAINT GREEN (-4475 1250);
DISPLAY INVISIBLE (-4475 1250);
FORCEPROP 1 LAST HDL_TAP TRUE
J 2
(-4800 1175);
DISPLAY 1.234043 (-4800 1175);
PAINT GREEN (-4800 1175);
DISPLAY INVISIBLE (-4800 1175);
FORCEPROP 1 LAST PATH I53
J 2
(-4473 1300);
DISPLAY 0.872340 (-4473 1300);
PAINT GREEN (-4473 1300);
DISPLAY INVISIBLE (-4473 1300);
FORCEADD TAP..6
R 2
(-4475 1450);
FORCEPROP 3 LASTPIN (-4525 1450) SIG_NAME M_H_DQ<5>
J 0
(-4515 1460);
DISPLAY 0.659574 (-4515 1460);
PAINT MONO (-4515 1460);
DISPLAY INVISIBLE (-4515 1460);
FORCEPROP 1 LASTPIN (-4525 1450) BN 5
J 2
(-4475 1460);
DISPLAY 0.617021 (-4475 1460);
PAINT PINK (-4475 1460);
FORCEPROP 2 LAST CDS_LIB mstr_standard
J 2
(-4475 1450);
DISPLAY 0.787234 (-4475 1450);
PAINT MONO (-4475 1450);
DISPLAY INVISIBLE (-4475 1450);
FORCEPROP 1 LAST BODY_TYPE PLUMBING
J 2
(-4475 1400);
DISPLAY 1.234043 (-4475 1400);
PAINT GREEN (-4475 1400);
DISPLAY INVISIBLE (-4475 1400);
FORCEPROP 1 LAST HDL_TAP TRUE
J 2
(-4800 1325);
DISPLAY 1.234043 (-4800 1325);
PAINT GREEN (-4800 1325);
DISPLAY INVISIBLE (-4800 1325);
FORCEPROP 1 LAST PATH I54
J 2
(-4473 1450);
DISPLAY 0.872340 (-4473 1450);
PAINT GREEN (-4473 1450);
DISPLAY INVISIBLE (-4473 1450);
FORCEADD TAP..6
R 2
(-4475 1400);
FORCEPROP 3 LASTPIN (-4525 1400) SIG_NAME M_H_DQ<4>
J 0
(-4515 1410);
DISPLAY 0.659574 (-4515 1410);
PAINT MONO (-4515 1410);
DISPLAY INVISIBLE (-4515 1410);
FORCEPROP 1 LASTPIN (-4525 1400) BN 4
J 2
(-4475 1410);
DISPLAY 0.617021 (-4475 1410);
PAINT PINK (-4475 1410);
FORCEPROP 2 LAST CDS_LIB mstr_standard
J 2
(-4475 1400);
DISPLAY 0.787234 (-4475 1400);
PAINT MONO (-4475 1400);
DISPLAY INVISIBLE (-4475 1400);
FORCEPROP 1 LAST BODY_TYPE PLUMBING
J 2
(-4475 1350);
DISPLAY 1.234043 (-4475 1350);
PAINT GREEN (-4475 1350);
DISPLAY INVISIBLE (-4475 1350);
FORCEPROP 1 LAST HDL_TAP TRUE
J 2
(-4800 1275);
DISPLAY 1.234043 (-4800 1275);
PAINT GREEN (-4800 1275);
DISPLAY INVISIBLE (-4800 1275);
FORCEPROP 1 LAST PATH I55
J 2
(-4473 1400);
DISPLAY 0.872340 (-4473 1400);
PAINT GREEN (-4473 1400);
DISPLAY INVISIBLE (-4473 1400);
FORCEADD SCONN288_H44441003..4
(-3075 1450);
FORCEPROP 1 LAST LOCATION J9U1
J 0
(-3525 2550);
DISPLAY 0.617021 (-3525 2550);
PAINT AQUA (-3525 2550);
FORCEPROP 1 LAST PART_NUMBER H44441-003
J 0
(-3525 400);
DISPLAY 0.617021 (-3525 400);
PAINT BLUE (-3525 400);
FORCEPROP 1 LAST MATERIAL SCONN
J 0
(-3525 2500);
DISPLAY 0.617021 (-3525 2500);
PAINT SKYBLUE (-3525 2500);
FORCEPROP 2 LASTPIN (-3575 2000) $PN 77
J 2
(-3585 2010);
DISPLAY 0.617021 (-3585 2010);
PAINT ORANGE (-3585 2010);
FORCEPROP 2 LASTPIN (-3575 1950) $PN 221
J 2
(-3585 1960);
DISPLAY 0.617021 (-3585 1960);
PAINT ORANGE (-3585 1960);
FORCEPROP 2 LASTPIN (-3575 2250) $PN 143
J 2
(-3585 2260);
DISPLAY 0.617021 (-3585 2260);
PAINT ORANGE (-3585 2260);
FORCEPROP 2 LASTPIN (-3575 2200) $PN 288
J 2
(-3585 2210);
DISPLAY 0.617021 (-3585 2210);
PAINT ORANGE (-3585 2210);
FORCEPROP 2 LASTPIN (-3575 2150) $PN 286
J 2
(-3585 2160);
DISPLAY 0.617021 (-3585 2160);
PAINT ORANGE (-3585 2160);
FORCEPROP 2 LASTPIN (-3575 2100) $PN 287
J 2
(-3585 2110);
DISPLAY 0.617021 (-3585 2110);
PAINT ORANGE (-3585 2110);
FORCEPROP 2 LASTPIN (-3575 1850) $PN 59
J 2
(-3585 1860);
DISPLAY 0.617021 (-3585 1860);
PAINT ORANGE (-3585 1860);
FORCEPROP 2 LASTPIN (-3575 1800) $PN 61
J 2
(-3585 1810);
DISPLAY 0.617021 (-3585 1810);
PAINT ORANGE (-3585 1810);
FORCEPROP 2 LASTPIN (-3575 1750) $PN 64
J 2
(-3585 1760);
DISPLAY 0.617021 (-3585 1760);
PAINT ORANGE (-3585 1760);
FORCEPROP 2 LASTPIN (-3575 1700) $PN 67
J 2
(-3585 1710);
DISPLAY 0.617021 (-3585 1710);
PAINT ORANGE (-3585 1710);
FORCEPROP 2 LASTPIN (-3575 1650) $PN 70
J 2
(-3585 1660);
DISPLAY 0.617021 (-3585 1660);
PAINT ORANGE (-3585 1660);
FORCEPROP 2 LASTPIN (-3575 1600) $PN 73
J 2
(-3585 1610);
DISPLAY 0.617021 (-3585 1610);
PAINT ORANGE (-3585 1610);
FORCEPROP 2 LASTPIN (-3575 1550) $PN 76
J 2
(-3585 1560);
DISPLAY 0.617021 (-3585 1560);
PAINT ORANGE (-3585 1560);
FORCEPROP 2 LASTPIN (-3575 1500) $PN 80
J 2
(-3585 1510);
DISPLAY 0.617021 (-3585 1510);
PAINT ORANGE (-3585 1510);
FORCEPROP 2 LASTPIN (-3575 1450) $PN 83
J 2
(-3585 1460);
DISPLAY 0.617021 (-3585 1460);
PAINT ORANGE (-3585 1460);
FORCEPROP 2 LASTPIN (-3575 1400) $PN 85
J 2
(-3585 1410);
DISPLAY 0.617021 (-3585 1410);
PAINT ORANGE (-3585 1410);
FORCEPROP 2 LASTPIN (-3575 1350) $PN 88
J 2
(-3585 1360);
DISPLAY 0.617021 (-3585 1360);
PAINT ORANGE (-3585 1360);
FORCEPROP 2 LASTPIN (-3575 1300) $PN 90
J 2
(-3585 1310);
DISPLAY 0.617021 (-3585 1310);
PAINT ORANGE (-3585 1310);
FORCEPROP 2 LASTPIN (-3575 1250) $PN 92
J 2
(-3585 1260);
DISPLAY 0.617021 (-3585 1260);
PAINT ORANGE (-3585 1260);
FORCEPROP 2 LASTPIN (-3575 1200) $PN 204
J 2
(-3585 1210);
DISPLAY 0.617021 (-3585 1210);
PAINT ORANGE (-3585 1210);
FORCEPROP 2 LASTPIN (-3575 1150) $PN 206
J 2
(-3585 1160);
DISPLAY 0.617021 (-3585 1160);
PAINT ORANGE (-3585 1160);
FORCEPROP 2 LASTPIN (-3575 1100) $PN 209
J 2
(-3585 1110);
DISPLAY 0.617021 (-3585 1110);
PAINT ORANGE (-3585 1110);
FORCEPROP 2 LASTPIN (-3575 1050) $PN 212
J 2
(-3585 1060);
DISPLAY 0.617021 (-3585 1060);
PAINT ORANGE (-3585 1060);
FORCEPROP 2 LASTPIN (-3575 1000) $PN 215
J 2
(-3585 1010);
DISPLAY 0.617021 (-3585 1010);
PAINT ORANGE (-3585 1010);
FORCEPROP 2 LASTPIN (-3575 950) $PN 217
J 2
(-3585 960);
DISPLAY 0.617021 (-3585 960);
PAINT ORANGE (-3585 960);
FORCEPROP 2 LASTPIN (-3575 900) $PN 220
J 2
(-3585 910);
DISPLAY 0.617021 (-3585 910);
PAINT ORANGE (-3585 910);
FORCEPROP 2 LASTPIN (-3575 850) $PN 223
J 2
(-3585 860);
DISPLAY 0.617021 (-3585 860);
PAINT ORANGE (-3585 860);
FORCEPROP 2 LASTPIN (-3575 800) $PN 226
J 2
(-3585 810);
DISPLAY 0.617021 (-3585 810);
PAINT ORANGE (-3585 810);
FORCEPROP 2 LASTPIN (-3575 750) $PN 229
J 2
(-3585 760);
DISPLAY 0.617021 (-3585 760);
PAINT ORANGE (-3585 760);
FORCEPROP 2 LASTPIN (-3575 700) $PN 231
J 2
(-3585 710);
DISPLAY 0.617021 (-3585 710);
PAINT ORANGE (-3585 710);
FORCEPROP 2 LASTPIN (-3575 650) $PN 233
J 2
(-3585 660);
DISPLAY 0.617021 (-3585 660);
PAINT ORANGE (-3585 660);
FORCEPROP 2 LASTPIN (-3575 600) $PN 236
J 2
(-3585 610);
DISPLAY 0.617021 (-3585 610);
PAINT ORANGE (-3585 610);
FORCEPROP 2 LASTPIN (-2575 2300) $PN 1
J 0
(-2565 2310);
DISPLAY 0.617021 (-2565 2310);
PAINT ORANGE (-2565 2310);
FORCEPROP 2 LASTPIN (-2575 2250) $PN 145
J 0
(-2565 2260);
DISPLAY 0.617021 (-2565 2260);
PAINT ORANGE (-2565 2260);
FORCEPROP 2 LASTPIN (-3575 2300) $PN 142
J 2
(-3585 2310);
DISPLAY 0.617021 (-3585 2310);
PAINT ORANGE (-3585 2310);
FORCEPROP 0 LAST BOM_SS NOPOP
J 0
(-3253 2486);
DISPLAY 1.021277 (-3253 2486);
PAINT BROWN (-3253 2486);
DISPLAY BOTH (-3253 2486);
FORCEPROP 1 LAST PACK_TYPE PIP
J 0
(-3525 2600);
PAINT SKYBLUE (-3525 2600);
DISPLAY INVISIBLE (-3525 2600);
FORCEPROP 2 LAST BOM_COST MEM
J 0
(-3075 1450);
PAINT ORANGE (-3075 1450);
DISPLAY INVISIBLE (-3075 1450);
FORCEPROP 2 LAST CDS_LIB mstr_sconn
J 0
(-3075 1450);
PAINT ORANGE (-3075 1450);
DISPLAY INVISIBLE (-3075 1450);
FORCEPROP 2 LAST SEC_TYPE PIP
J 0
(-3525 2600);
DISPLAY 1.021277 (-3525 2600);
PAINT ORANGE (-3525 2600);
DISPLAY INVISIBLE (-3525 2600);
FORCEPROP 2 LAST SEC 4
J 0
(-3525 2600);
DISPLAY 0.680851 (-3525 2600);
PAINT MONO (-3525 2600);
DISPLAY INVISIBLE (-3525 2600);
FORCEPROP 2 LAST CDS_LOCATION J9U1
J 0
(-3525 2550);
DISPLAY 0.617021 (-3525 2550);
PAINT AQUA (-3525 2550);
DISPLAY INVISIBLE (-3525 2550);
FORCEPROP 1 LAST PATH I56
J 0
(-3075 2500);
PAINT GREEN (-3075 2500);
DISPLAY INVISIBLE (-3075 2500);
FORCEPROP 2 LAST ROOM DDR4_GH_H
J 0
(-3075 1450);
PAINT ORANGE (-3075 1450);
DISPLAY INVISIBLE (-3075 1450);
FORCEADD TAP..6
R 2
(-4475 1550);
FORCEPROP 3 LASTPIN (-4525 1550) SIG_NAME M_H_DQ<7>
J 0
(-4515 1560);
DISPLAY 0.659574 (-4515 1560);
PAINT MONO (-4515 1560);
DISPLAY INVISIBLE (-4515 1560);
FORCEPROP 1 LASTPIN (-4525 1550) BN 7
J 2
(-4475 1560);
DISPLAY 0.617021 (-4475 1560);
PAINT PINK (-4475 1560);
FORCEPROP 2 LAST CDS_LIB mstr_standard
J 2
(-4475 1550);
DISPLAY 0.787234 (-4475 1550);
PAINT MONO (-4475 1550);
DISPLAY INVISIBLE (-4475 1550);
FORCEPROP 1 LAST BODY_TYPE PLUMBING
J 2
(-4475 1500);
DISPLAY 1.234043 (-4475 1500);
PAINT GREEN (-4475 1500);
DISPLAY INVISIBLE (-4475 1500);
FORCEPROP 1 LAST HDL_TAP TRUE
J 2
(-4800 1425);
DISPLAY 1.234043 (-4800 1425);
PAINT GREEN (-4800 1425);
DISPLAY INVISIBLE (-4800 1425);
FORCEPROP 1 LAST PATH I57
J 2
(-4473 1550);
DISPLAY 0.872340 (-4473 1550);
PAINT GREEN (-4473 1550);
DISPLAY INVISIBLE (-4473 1550);
FORCEADD TAP..6
R 2
(-4475 1500);
FORCEPROP 3 LASTPIN (-4525 1500) SIG_NAME M_H_DQ<6>
J 0
(-4515 1510);
DISPLAY 0.659574 (-4515 1510);
PAINT MONO (-4515 1510);
DISPLAY INVISIBLE (-4515 1510);
FORCEPROP 1 LASTPIN (-4525 1500) BN 6
J 2
(-4475 1510);
DISPLAY 0.617021 (-4475 1510);
PAINT PINK (-4475 1510);
FORCEPROP 2 LAST CDS_LIB mstr_standard
J 2
(-4475 1500);
DISPLAY 0.787234 (-4475 1500);
PAINT MONO (-4475 1500);
DISPLAY INVISIBLE (-4475 1500);
FORCEPROP 1 LAST BODY_TYPE PLUMBING
J 2
(-4475 1450);
DISPLAY 1.234043 (-4475 1450);
PAINT GREEN (-4475 1450);
DISPLAY INVISIBLE (-4475 1450);
FORCEPROP 1 LAST HDL_TAP TRUE
J 2
(-4800 1375);
DISPLAY 1.234043 (-4800 1375);
PAINT GREEN (-4800 1375);
DISPLAY INVISIBLE (-4800 1375);
FORCEPROP 1 LAST PATH I58
J 2
(-4473 1500);
DISPLAY 0.872340 (-4473 1500);
PAINT GREEN (-4473 1500);
DISPLAY INVISIBLE (-4473 1500);
FORCEADD TAP..6
R 2
(-4475 1600);
FORCEPROP 3 LASTPIN (-4525 1600) SIG_NAME M_H_DQ<8>
J 0
(-4515 1610);
DISPLAY 0.659574 (-4515 1610);
PAINT MONO (-4515 1610);
DISPLAY INVISIBLE (-4515 1610);
FORCEPROP 1 LASTPIN (-4525 1600) BN 8
J 2
(-4475 1610);
DISPLAY 0.617021 (-4475 1610);
PAINT PINK (-4475 1610);
FORCEPROP 2 LAST CDS_LIB mstr_standard
J 2
(-4475 1600);
DISPLAY 0.787234 (-4475 1600);
PAINT MONO (-4475 1600);
DISPLAY INVISIBLE (-4475 1600);
FORCEPROP 1 LAST BODY_TYPE PLUMBING
J 2
(-4475 1550);
DISPLAY 1.234043 (-4475 1550);
PAINT GREEN (-4475 1550);
DISPLAY INVISIBLE (-4475 1550);
FORCEPROP 1 LAST HDL_TAP TRUE
J 2
(-4800 1475);
DISPLAY 1.234043 (-4800 1475);
PAINT GREEN (-4800 1475);
DISPLAY INVISIBLE (-4800 1475);
FORCEPROP 1 LAST PATH I59
J 2
(-4473 1600);
DISPLAY 0.872340 (-4473 1600);
PAINT GREEN (-4473 1600);
DISPLAY INVISIBLE (-4473 1600);
FORCEADD OFFPAGE..1
(-6625 1300);
FORCEPROP 2 LAST $XR5 82 
J 0
(-7326 1300);
DISPLAY 0.638298 (-7326 1300);
PAINT MONO (-7326 1300);
FORCEPROP 2 LAST $XR4 81 
J 0
(-7236 1300);
DISPLAY 0.638298 (-7236 1300);
PAINT MONO (-7236 1300);
FORCEPROP 2 LAST $XR3 79 
J 0
(-7146 1300);
DISPLAY 0.638298 (-7146 1300);
PAINT MONO (-7146 1300);
FORCEPROP 2 LAST $XR2 78 
J 0
(-7056 1300);
DISPLAY 0.638298 (-7056 1300);
PAINT MONO (-7056 1300);
FORCEPROP 2 LAST $XR1 77 
J 0
(-6966 1300);
DISPLAY 0.638298 (-6966 1300);
PAINT MONO (-6966 1300);
FORCEPROP 2 LAST $XR0 99 
J 0
(-6876 1300);
DISPLAY 0.638298 (-6876 1300);
PAINT MONO (-6876 1300);
FORCEPROP 2 LAST CDS_LIB mstr_standard
J 0
(-6625 1300);
DISPLAY 0.787234 (-6625 1300);
PAINT MONO (-6625 1300);
DISPLAY INVISIBLE (-6625 1300);
FORCEPROP 1 LAST OFFPAGE TRUE
J 0
(-6300 1175);
DISPLAY 0.936170 (-6300 1175);
PAINT GREEN (-6300 1175);
DISPLAY INVISIBLE (-6300 1175);
FORCEPROP 1 LAST COMMENT_BODY TRUE
J 0
(-6500 1200);
DISPLAY 0.936170 (-6500 1200);
PAINT GREEN (-6500 1200);
DISPLAY INVISIBLE (-6500 1200);
FORCEPROP 2 LAST PATH I6
J 0
(-6875 1350);
DISPLAY 1.021277 (-6875 1350);
PAINT ORANGE (-6875 1350);
DISPLAY INVISIBLE (-6875 1350);
FORCEADD TAP..6
R 2
(-4475 1650);
FORCEPROP 3 LASTPIN (-4525 1650) SIG_NAME M_H_DQ<9>
J 0
(-4515 1660);
DISPLAY 0.659574 (-4515 1660);
PAINT MONO (-4515 1660);
DISPLAY INVISIBLE (-4515 1660);
FORCEPROP 1 LASTPIN (-4525 1650) BN 9
J 2
(-4475 1660);
DISPLAY 0.617021 (-4475 1660);
PAINT PINK (-4475 1660);
FORCEPROP 2 LAST CDS_LIB mstr_standard
J 2
(-4475 1650);
DISPLAY 0.787234 (-4475 1650);
PAINT MONO (-4475 1650);
DISPLAY INVISIBLE (-4475 1650);
FORCEPROP 1 LAST BODY_TYPE PLUMBING
J 2
(-4475 1600);
DISPLAY 1.234043 (-4475 1600);
PAINT GREEN (-4475 1600);
DISPLAY INVISIBLE (-4475 1600);
FORCEPROP 1 LAST HDL_TAP TRUE
J 2
(-4800 1525);
DISPLAY 1.234043 (-4800 1525);
PAINT GREEN (-4800 1525);
DISPLAY INVISIBLE (-4800 1525);
FORCEPROP 1 LAST PATH I60
J 2
(-4473 1650);
DISPLAY 0.872340 (-4473 1650);
PAINT GREEN (-4473 1650);
DISPLAY INVISIBLE (-4473 1650);
FORCEADD TAP..6
R 2
(-4475 1700);
FORCEPROP 3 LASTPIN (-4525 1700) SIG_NAME M_H_DQ<10>
J 0
(-4515 1710);
DISPLAY 0.659574 (-4515 1710);
PAINT MONO (-4515 1710);
DISPLAY INVISIBLE (-4515 1710);
FORCEPROP 1 LASTPIN (-4525 1700) BN 10
J 2
(-4475 1710);
DISPLAY 0.617021 (-4475 1710);
PAINT PINK (-4475 1710);
FORCEPROP 2 LAST CDS_LIB mstr_standard
J 2
(-4475 1700);
DISPLAY 0.787234 (-4475 1700);
PAINT MONO (-4475 1700);
DISPLAY INVISIBLE (-4475 1700);
FORCEPROP 1 LAST BODY_TYPE PLUMBING
J 2
(-4475 1650);
DISPLAY 1.234043 (-4475 1650);
PAINT GREEN (-4475 1650);
DISPLAY INVISIBLE (-4475 1650);
FORCEPROP 1 LAST HDL_TAP TRUE
J 2
(-4800 1575);
DISPLAY 1.234043 (-4800 1575);
PAINT GREEN (-4800 1575);
DISPLAY INVISIBLE (-4800 1575);
FORCEPROP 1 LAST PATH I61
J 2
(-4473 1700);
DISPLAY 0.872340 (-4473 1700);
PAINT GREEN (-4473 1700);
DISPLAY INVISIBLE (-4473 1700);
FORCEADD TAP..6
R 2
(-4475 1750);
FORCEPROP 3 LASTPIN (-4525 1750) SIG_NAME M_H_DQ<11>
J 0
(-4515 1760);
DISPLAY 0.659574 (-4515 1760);
PAINT MONO (-4515 1760);
DISPLAY INVISIBLE (-4515 1760);
FORCEPROP 1 LASTPIN (-4525 1750) BN 11
J 2
(-4475 1760);
DISPLAY 0.617021 (-4475 1760);
PAINT PINK (-4475 1760);
FORCEPROP 2 LAST CDS_LIB mstr_standard
J 2
(-4475 1750);
DISPLAY 0.787234 (-4475 1750);
PAINT MONO (-4475 1750);
DISPLAY INVISIBLE (-4475 1750);
FORCEPROP 1 LAST BODY_TYPE PLUMBING
J 2
(-4475 1700);
DISPLAY 1.234043 (-4475 1700);
PAINT GREEN (-4475 1700);
DISPLAY INVISIBLE (-4475 1700);
FORCEPROP 1 LAST HDL_TAP TRUE
J 2
(-4800 1625);
DISPLAY 1.234043 (-4800 1625);
PAINT GREEN (-4800 1625);
DISPLAY INVISIBLE (-4800 1625);
FORCEPROP 1 LAST PATH I62
J 2
(-4473 1750);
DISPLAY 0.872340 (-4473 1750);
PAINT GREEN (-4473 1750);
DISPLAY INVISIBLE (-4473 1750);
FORCEADD TAP..6
R 2
(-4475 1850);
FORCEPROP 3 LASTPIN (-4525 1850) SIG_NAME M_H_DQ<13>
J 0
(-4515 1860);
DISPLAY 0.659574 (-4515 1860);
PAINT MONO (-4515 1860);
DISPLAY INVISIBLE (-4515 1860);
FORCEPROP 1 LASTPIN (-4525 1850) BN 13
J 2
(-4475 1860);
DISPLAY 0.617021 (-4475 1860);
PAINT PINK (-4475 1860);
FORCEPROP 2 LAST CDS_LIB mstr_standard
J 2
(-4475 1850);
DISPLAY 0.787234 (-4475 1850);
PAINT MONO (-4475 1850);
DISPLAY INVISIBLE (-4475 1850);
FORCEPROP 1 LAST BODY_TYPE PLUMBING
J 2
(-4475 1800);
DISPLAY 1.234043 (-4475 1800);
PAINT GREEN (-4475 1800);
DISPLAY INVISIBLE (-4475 1800);
FORCEPROP 1 LAST HDL_TAP TRUE
J 2
(-4800 1725);
DISPLAY 1.234043 (-4800 1725);
PAINT GREEN (-4800 1725);
DISPLAY INVISIBLE (-4800 1725);
FORCEPROP 1 LAST PATH I63
J 2
(-4473 1850);
DISPLAY 0.872340 (-4473 1850);
PAINT GREEN (-4473 1850);
DISPLAY INVISIBLE (-4473 1850);
FORCEADD TAP..6
R 2
(-4475 1800);
FORCEPROP 3 LASTPIN (-4525 1800) SIG_NAME M_H_DQ<12>
J 0
(-4515 1810);
DISPLAY 0.659574 (-4515 1810);
PAINT MONO (-4515 1810);
DISPLAY INVISIBLE (-4515 1810);
FORCEPROP 1 LASTPIN (-4525 1800) BN 12
J 2
(-4475 1810);
DISPLAY 0.617021 (-4475 1810);
PAINT PINK (-4475 1810);
FORCEPROP 2 LAST CDS_LIB mstr_standard
J 2
(-4475 1800);
DISPLAY 0.787234 (-4475 1800);
PAINT MONO (-4475 1800);
DISPLAY INVISIBLE (-4475 1800);
FORCEPROP 1 LAST BODY_TYPE PLUMBING
J 2
(-4475 1750);
DISPLAY 1.234043 (-4475 1750);
PAINT GREEN (-4475 1750);
DISPLAY INVISIBLE (-4475 1750);
FORCEPROP 1 LAST HDL_TAP TRUE
J 2
(-4800 1675);
DISPLAY 1.234043 (-4800 1675);
PAINT GREEN (-4800 1675);
DISPLAY INVISIBLE (-4800 1675);
FORCEPROP 1 LAST PATH I64
J 2
(-4473 1800);
DISPLAY 0.872340 (-4473 1800);
PAINT GREEN (-4473 1800);
DISPLAY INVISIBLE (-4473 1800);
FORCEADD TAP..6
R 2
(-4475 2000);
FORCEPROP 3 LASTPIN (-4525 2000) SIG_NAME M_H_DQ<16>
J 0
(-4515 2010);
DISPLAY 0.659574 (-4515 2010);
PAINT MONO (-4515 2010);
DISPLAY INVISIBLE (-4515 2010);
FORCEPROP 1 LASTPIN (-4525 2000) BN 16
J 2
(-4475 2010);
DISPLAY 0.617021 (-4475 2010);
PAINT PINK (-4475 2010);
FORCEPROP 2 LAST CDS_LIB mstr_standard
J 2
(-4475 2000);
DISPLAY 0.787234 (-4475 2000);
PAINT MONO (-4475 2000);
DISPLAY INVISIBLE (-4475 2000);
FORCEPROP 1 LAST BODY_TYPE PLUMBING
J 2
(-4475 1950);
DISPLAY 1.234043 (-4475 1950);
PAINT GREEN (-4475 1950);
DISPLAY INVISIBLE (-4475 1950);
FORCEPROP 1 LAST HDL_TAP TRUE
J 2
(-4800 1875);
DISPLAY 1.234043 (-4800 1875);
PAINT GREEN (-4800 1875);
DISPLAY INVISIBLE (-4800 1875);
FORCEPROP 1 LAST PATH I65
J 2
(-4473 2000);
DISPLAY 0.872340 (-4473 2000);
PAINT GREEN (-4473 2000);
DISPLAY INVISIBLE (-4473 2000);
FORCEADD TAP..6
R 2
(-4475 1900);
FORCEPROP 3 LASTPIN (-4525 1900) SIG_NAME M_H_DQ<14>
J 0
(-4515 1910);
DISPLAY 0.659574 (-4515 1910);
PAINT MONO (-4515 1910);
DISPLAY INVISIBLE (-4515 1910);
FORCEPROP 1 LASTPIN (-4525 1900) BN 14
J 2
(-4475 1910);
DISPLAY 0.617021 (-4475 1910);
PAINT PINK (-4475 1910);
FORCEPROP 2 LAST CDS_LIB mstr_standard
J 2
(-4475 1900);
DISPLAY 0.787234 (-4475 1900);
PAINT MONO (-4475 1900);
DISPLAY INVISIBLE (-4475 1900);
FORCEPROP 1 LAST BODY_TYPE PLUMBING
J 2
(-4475 1850);
DISPLAY 1.234043 (-4475 1850);
PAINT GREEN (-4475 1850);
DISPLAY INVISIBLE (-4475 1850);
FORCEPROP 1 LAST HDL_TAP TRUE
J 2
(-4800 1775);
DISPLAY 1.234043 (-4800 1775);
PAINT GREEN (-4800 1775);
DISPLAY INVISIBLE (-4800 1775);
FORCEPROP 1 LAST PATH I66
J 2
(-4473 1900);
DISPLAY 0.872340 (-4473 1900);
PAINT GREEN (-4473 1900);
DISPLAY INVISIBLE (-4473 1900);
FORCEADD TAP..6
R 2
(-4475 1950);
FORCEPROP 3 LASTPIN (-4525 1950) SIG_NAME M_H_DQ<15>
J 0
(-4515 1960);
DISPLAY 0.659574 (-4515 1960);
PAINT MONO (-4515 1960);
DISPLAY INVISIBLE (-4515 1960);
FORCEPROP 1 LASTPIN (-4525 1950) BN 15
J 2
(-4475 1960);
DISPLAY 0.617021 (-4475 1960);
PAINT PINK (-4475 1960);
FORCEPROP 2 LAST CDS_LIB mstr_standard
J 2
(-4475 1950);
DISPLAY 0.787234 (-4475 1950);
PAINT MONO (-4475 1950);
DISPLAY INVISIBLE (-4475 1950);
FORCEPROP 1 LAST BODY_TYPE PLUMBING
J 2
(-4475 1900);
DISPLAY 1.234043 (-4475 1900);
PAINT GREEN (-4475 1900);
DISPLAY INVISIBLE (-4475 1900);
FORCEPROP 1 LAST HDL_TAP TRUE
J 2
(-4800 1825);
DISPLAY 1.234043 (-4800 1825);
PAINT GREEN (-4800 1825);
DISPLAY INVISIBLE (-4800 1825);
FORCEPROP 1 LAST PATH I67
J 2
(-4473 1950);
DISPLAY 0.872340 (-4473 1950);
PAINT GREEN (-4473 1950);
DISPLAY INVISIBLE (-4473 1950);
FORCEADD TAP..6
R 2
(-4475 2050);
FORCEPROP 3 LASTPIN (-4525 2050) SIG_NAME M_H_DQ<17>
J 0
(-4515 2060);
DISPLAY 0.659574 (-4515 2060);
PAINT MONO (-4515 2060);
DISPLAY INVISIBLE (-4515 2060);
FORCEPROP 1 LASTPIN (-4525 2050) BN 17
J 2
(-4475 2060);
DISPLAY 0.617021 (-4475 2060);
PAINT PINK (-4475 2060);
FORCEPROP 2 LAST CDS_LIB mstr_standard
J 2
(-4475 2050);
DISPLAY 0.787234 (-4475 2050);
PAINT MONO (-4475 2050);
DISPLAY INVISIBLE (-4475 2050);
FORCEPROP 1 LAST BODY_TYPE PLUMBING
J 2
(-4475 2000);
DISPLAY 1.234043 (-4475 2000);
PAINT GREEN (-4475 2000);
DISPLAY INVISIBLE (-4475 2000);
FORCEPROP 1 LAST HDL_TAP TRUE
J 2
(-4800 1925);
DISPLAY 1.234043 (-4800 1925);
PAINT GREEN (-4800 1925);
DISPLAY INVISIBLE (-4800 1925);
FORCEPROP 1 LAST PATH I68
J 2
(-4473 2050);
DISPLAY 0.872340 (-4473 2050);
PAINT GREEN (-4473 2050);
DISPLAY INVISIBLE (-4473 2050);
FORCEADD TAP..6
R 2
(-4475 2100);
FORCEPROP 3 LASTPIN (-4525 2100) SIG_NAME M_H_DQ<18>
J 0
(-4515 2110);
DISPLAY 0.659574 (-4515 2110);
PAINT MONO (-4515 2110);
DISPLAY INVISIBLE (-4515 2110);
FORCEPROP 1 LASTPIN (-4525 2100) BN 18
J 2
(-4475 2110);
DISPLAY 0.617021 (-4475 2110);
PAINT PINK (-4475 2110);
FORCEPROP 2 LAST CDS_LIB mstr_standard
J 2
(-4475 2100);
DISPLAY 0.787234 (-4475 2100);
PAINT MONO (-4475 2100);
DISPLAY INVISIBLE (-4475 2100);
FORCEPROP 1 LAST BODY_TYPE PLUMBING
J 2
(-4475 2050);
DISPLAY 1.234043 (-4475 2050);
PAINT GREEN (-4475 2050);
DISPLAY INVISIBLE (-4475 2050);
FORCEPROP 1 LAST HDL_TAP TRUE
J 2
(-4800 1975);
DISPLAY 1.234043 (-4800 1975);
PAINT GREEN (-4800 1975);
DISPLAY INVISIBLE (-4800 1975);
FORCEPROP 1 LAST PATH I69
J 2
(-4473 2100);
DISPLAY 0.872340 (-4473 2100);
PAINT GREEN (-4473 2100);
DISPLAY INVISIBLE (-4473 2100);
FORCEADD OFFPAGE..6
(-6625 1350);
FORCEPROP 2 LASTPIN (-6575 1350) SIG_NAME SMB_DDR_GHJ_VPP_SDA
J 0
(-6535 1360);
DISPLAY 0.617021 (-6535 1360);
PAINT ORANGE (-6535 1360);
FORCEPROP 2 LAST $XR5 99 
J 0
(-7324 1350);
DISPLAY 0.638298 (-7324 1350);
PAINT MONO (-7324 1350);
FORCEPROP 2 LAST $XR4 82 
J 0
(-7234 1350);
DISPLAY 0.638298 (-7234 1350);
PAINT MONO (-7234 1350);
FORCEPROP 2 LAST $XR3 81 
J 0
(-7144 1350);
DISPLAY 0.638298 (-7144 1350);
PAINT MONO (-7144 1350);
FORCEPROP 2 LAST $XR2 79 
J 0
(-7054 1350);
DISPLAY 0.638298 (-7054 1350);
PAINT MONO (-7054 1350);
FORCEPROP 2 LAST $XR1 78 
J 0
(-6964 1350);
DISPLAY 0.638298 (-6964 1350);
PAINT MONO (-6964 1350);
FORCEPROP 2 LAST $XR0 77 
J 0
(-6874 1350);
DISPLAY 0.638298 (-6874 1350);
PAINT MONO (-6874 1350);
FORCEPROP 2 LAST CDS_LIB mstr_standard
J 0
(-6625 1350);
DISPLAY 0.787234 (-6625 1350);
PAINT MONO (-6625 1350);
DISPLAY INVISIBLE (-6625 1350);
FORCEPROP 1 LAST OFFPAGE TRUE
J 0
(-6300 1225);
DISPLAY 0.936170 (-6300 1225);
PAINT GREEN (-6300 1225);
DISPLAY INVISIBLE (-6300 1225);
FORCEPROP 1 LAST COMMENT_BODY TRUE
J 0
(-6525 1275);
DISPLAY 0.936170 (-6525 1275);
PAINT GREEN (-6525 1275);
DISPLAY INVISIBLE (-6525 1275);
FORCEPROP 2 LAST PATH I7
J 0
(-6850 1400);
DISPLAY 1.021277 (-6850 1400);
PAINT ORANGE (-6850 1400);
DISPLAY INVISIBLE (-6850 1400);
FORCEADD TAP..6
R 2
(-4475 2250);
FORCEPROP 3 LASTPIN (-4525 2250) SIG_NAME M_H_DQ<21>
J 0
(-4515 2260);
DISPLAY 0.659574 (-4515 2260);
PAINT MONO (-4515 2260);
DISPLAY INVISIBLE (-4515 2260);
FORCEPROP 1 LASTPIN (-4525 2250) BN 21
J 2
(-4475 2260);
DISPLAY 0.617021 (-4475 2260);
PAINT PINK (-4475 2260);
FORCEPROP 2 LAST CDS_LIB mstr_standard
J 2
(-4475 2250);
DISPLAY 0.787234 (-4475 2250);
PAINT MONO (-4475 2250);
DISPLAY INVISIBLE (-4475 2250);
FORCEPROP 1 LAST BODY_TYPE PLUMBING
J 2
(-4475 2200);
DISPLAY 1.234043 (-4475 2200);
PAINT GREEN (-4475 2200);
DISPLAY INVISIBLE (-4475 2200);
FORCEPROP 1 LAST HDL_TAP TRUE
J 2
(-4800 2125);
DISPLAY 1.234043 (-4800 2125);
PAINT GREEN (-4800 2125);
DISPLAY INVISIBLE (-4800 2125);
FORCEPROP 1 LAST PATH I70
J 2
(-4473 2250);
DISPLAY 0.872340 (-4473 2250);
PAINT GREEN (-4473 2250);
DISPLAY INVISIBLE (-4473 2250);
FORCEADD TAP..6
R 2
(-4475 2150);
FORCEPROP 3 LASTPIN (-4525 2150) SIG_NAME M_H_DQ<19>
J 0
(-4515 2160);
DISPLAY 0.659574 (-4515 2160);
PAINT MONO (-4515 2160);
DISPLAY INVISIBLE (-4515 2160);
FORCEPROP 1 LASTPIN (-4525 2150) BN 19
J 2
(-4475 2160);
DISPLAY 0.617021 (-4475 2160);
PAINT PINK (-4475 2160);
FORCEPROP 2 LAST CDS_LIB mstr_standard
J 2
(-4475 2150);
DISPLAY 0.787234 (-4475 2150);
PAINT MONO (-4475 2150);
DISPLAY INVISIBLE (-4475 2150);
FORCEPROP 1 LAST BODY_TYPE PLUMBING
J 2
(-4475 2100);
DISPLAY 1.234043 (-4475 2100);
PAINT GREEN (-4475 2100);
DISPLAY INVISIBLE (-4475 2100);
FORCEPROP 1 LAST HDL_TAP TRUE
J 2
(-4800 2025);
DISPLAY 1.234043 (-4800 2025);
PAINT GREEN (-4800 2025);
DISPLAY INVISIBLE (-4800 2025);
FORCEPROP 1 LAST PATH I71
J 2
(-4473 2150);
DISPLAY 0.872340 (-4473 2150);
PAINT GREEN (-4473 2150);
DISPLAY INVISIBLE (-4473 2150);
FORCEADD TAP..6
R 2
(-4475 2200);
FORCEPROP 3 LASTPIN (-4525 2200) SIG_NAME M_H_DQ<20>
J 0
(-4515 2210);
DISPLAY 0.659574 (-4515 2210);
PAINT MONO (-4515 2210);
DISPLAY INVISIBLE (-4515 2210);
FORCEPROP 1 LASTPIN (-4525 2200) BN 20
J 2
(-4475 2210);
DISPLAY 0.617021 (-4475 2210);
PAINT PINK (-4475 2210);
FORCEPROP 2 LAST CDS_LIB mstr_standard
J 2
(-4475 2200);
DISPLAY 0.787234 (-4475 2200);
PAINT MONO (-4475 2200);
DISPLAY INVISIBLE (-4475 2200);
FORCEPROP 1 LAST BODY_TYPE PLUMBING
J 2
(-4475 2150);
DISPLAY 1.234043 (-4475 2150);
PAINT GREEN (-4475 2150);
DISPLAY INVISIBLE (-4475 2150);
FORCEPROP 1 LAST HDL_TAP TRUE
J 2
(-4800 2075);
DISPLAY 1.234043 (-4800 2075);
PAINT GREEN (-4800 2075);
DISPLAY INVISIBLE (-4800 2075);
FORCEPROP 1 LAST PATH I72
J 2
(-4473 2200);
DISPLAY 0.872340 (-4473 2200);
PAINT GREEN (-4473 2200);
DISPLAY INVISIBLE (-4473 2200);
FORCEADD TAP..6
R 2
(-4475 2300);
FORCEPROP 3 LASTPIN (-4525 2300) SIG_NAME M_H_DQ<22>
J 0
(-4515 2310);
DISPLAY 0.659574 (-4515 2310);
PAINT MONO (-4515 2310);
DISPLAY INVISIBLE (-4515 2310);
FORCEPROP 1 LASTPIN (-4525 2300) BN 22
J 2
(-4475 2310);
DISPLAY 0.617021 (-4475 2310);
PAINT PINK (-4475 2310);
FORCEPROP 2 LAST CDS_LIB mstr_standard
J 2
(-4475 2300);
DISPLAY 0.787234 (-4475 2300);
PAINT MONO (-4475 2300);
DISPLAY INVISIBLE (-4475 2300);
FORCEPROP 1 LAST BODY_TYPE PLUMBING
J 2
(-4475 2250);
DISPLAY 1.234043 (-4475 2250);
PAINT GREEN (-4475 2250);
DISPLAY INVISIBLE (-4475 2250);
FORCEPROP 1 LAST HDL_TAP TRUE
J 2
(-4800 2175);
DISPLAY 1.234043 (-4800 2175);
PAINT GREEN (-4800 2175);
DISPLAY INVISIBLE (-4800 2175);
FORCEPROP 1 LAST PATH I73
J 2
(-4473 2300);
DISPLAY 0.872340 (-4473 2300);
PAINT GREEN (-4473 2300);
DISPLAY INVISIBLE (-4473 2300);
FORCEADD TAP..6
R 2
(-4475 2350);
FORCEPROP 3 LASTPIN (-4525 2350) SIG_NAME M_H_DQ<23>
J 0
(-4515 2360);
DISPLAY 0.659574 (-4515 2360);
PAINT MONO (-4515 2360);
DISPLAY INVISIBLE (-4515 2360);
FORCEPROP 1 LASTPIN (-4525 2350) BN 23
J 2
(-4475 2360);
DISPLAY 0.617021 (-4475 2360);
PAINT PINK (-4475 2360);
FORCEPROP 2 LAST CDS_LIB mstr_standard
J 2
(-4475 2350);
DISPLAY 0.787234 (-4475 2350);
PAINT MONO (-4475 2350);
DISPLAY INVISIBLE (-4475 2350);
FORCEPROP 1 LAST BODY_TYPE PLUMBING
J 2
(-4475 2300);
DISPLAY 1.234043 (-4475 2300);
PAINT GREEN (-4475 2300);
DISPLAY INVISIBLE (-4475 2300);
FORCEPROP 1 LAST HDL_TAP TRUE
J 2
(-4800 2225);
DISPLAY 1.234043 (-4800 2225);
PAINT GREEN (-4800 2225);
DISPLAY INVISIBLE (-4800 2225);
FORCEPROP 1 LAST PATH I74
J 2
(-4473 2350);
DISPLAY 0.872340 (-4473 2350);
PAINT GREEN (-4473 2350);
DISPLAY INVISIBLE (-4473 2350);
FORCEADD TAP..6
R 2
(-4475 2500);
FORCEPROP 3 LASTPIN (-4525 2500) SIG_NAME M_H_DQ<26>
J 0
(-4515 2510);
DISPLAY 0.659574 (-4515 2510);
PAINT MONO (-4515 2510);
DISPLAY INVISIBLE (-4515 2510);
FORCEPROP 1 LASTPIN (-4525 2500) BN 26
J 2
(-4475 2510);
DISPLAY 0.617021 (-4475 2510);
PAINT PINK (-4475 2510);
FORCEPROP 2 LAST CDS_LIB mstr_standard
J 2
(-4475 2500);
DISPLAY 0.787234 (-4475 2500);
PAINT MONO (-4475 2500);
DISPLAY INVISIBLE (-4475 2500);
FORCEPROP 1 LAST BODY_TYPE PLUMBING
J 2
(-4475 2450);
DISPLAY 1.234043 (-4475 2450);
PAINT GREEN (-4475 2450);
DISPLAY INVISIBLE (-4475 2450);
FORCEPROP 1 LAST HDL_TAP TRUE
J 2
(-4800 2375);
DISPLAY 1.234043 (-4800 2375);
PAINT GREEN (-4800 2375);
DISPLAY INVISIBLE (-4800 2375);
FORCEPROP 1 LAST PATH I75
J 2
(-4473 2500);
DISPLAY 0.872340 (-4473 2500);
PAINT GREEN (-4473 2500);
DISPLAY INVISIBLE (-4473 2500);
FORCEADD TAP..6
R 2
(-4475 2450);
FORCEPROP 3 LASTPIN (-4525 2450) SIG_NAME M_H_DQ<25>
J 0
(-4515 2460);
DISPLAY 0.659574 (-4515 2460);
PAINT MONO (-4515 2460);
DISPLAY INVISIBLE (-4515 2460);
FORCEPROP 1 LASTPIN (-4525 2450) BN 25
J 2
(-4475 2460);
DISPLAY 0.617021 (-4475 2460);
PAINT PINK (-4475 2460);
FORCEPROP 2 LAST CDS_LIB mstr_standard
J 2
(-4475 2450);
DISPLAY 0.787234 (-4475 2450);
PAINT MONO (-4475 2450);
DISPLAY INVISIBLE (-4475 2450);
FORCEPROP 1 LAST BODY_TYPE PLUMBING
J 2
(-4475 2400);
DISPLAY 1.234043 (-4475 2400);
PAINT GREEN (-4475 2400);
DISPLAY INVISIBLE (-4475 2400);
FORCEPROP 1 LAST HDL_TAP TRUE
J 2
(-4800 2325);
DISPLAY 1.234043 (-4800 2325);
PAINT GREEN (-4800 2325);
DISPLAY INVISIBLE (-4800 2325);
FORCEPROP 1 LAST PATH I76
J 2
(-4473 2450);
DISPLAY 0.872340 (-4473 2450);
PAINT GREEN (-4473 2450);
DISPLAY INVISIBLE (-4473 2450);
FORCEADD TAP..6
R 2
(-4475 2400);
FORCEPROP 3 LASTPIN (-4525 2400) SIG_NAME M_H_DQ<24>
J 0
(-4515 2410);
DISPLAY 0.659574 (-4515 2410);
PAINT MONO (-4515 2410);
DISPLAY INVISIBLE (-4515 2410);
FORCEPROP 1 LASTPIN (-4525 2400) BN 24
J 2
(-4475 2410);
DISPLAY 0.617021 (-4475 2410);
PAINT PINK (-4475 2410);
FORCEPROP 2 LAST CDS_LIB mstr_standard
J 2
(-4475 2400);
DISPLAY 0.787234 (-4475 2400);
PAINT MONO (-4475 2400);
DISPLAY INVISIBLE (-4475 2400);
FORCEPROP 1 LAST BODY_TYPE PLUMBING
J 2
(-4475 2350);
DISPLAY 1.234043 (-4475 2350);
PAINT GREEN (-4475 2350);
DISPLAY INVISIBLE (-4475 2350);
FORCEPROP 1 LAST HDL_TAP TRUE
J 2
(-4800 2275);
DISPLAY 1.234043 (-4800 2275);
PAINT GREEN (-4800 2275);
DISPLAY INVISIBLE (-4800 2275);
FORCEPROP 1 LAST PATH I77
J 2
(-4473 2400);
DISPLAY 0.872340 (-4473 2400);
PAINT GREEN (-4473 2400);
DISPLAY INVISIBLE (-4473 2400);
FORCEADD PVDDQ_GHJ..1
(-4175 1975);
FORCEPROP 3 LASTPIN (-4175 1925) SIG_NAME PVDDQ_GHJ\g
J 0
(-4165 1935);
DISPLAY 0.659574 (-4165 1935);
PAINT MONO (-4165 1935);
DISPLAY INVISIBLE (-4165 1935);
FORCEPROP 1 LAST VOLTAGE 1.2V
J 0
(-4220 1932);
DISPLAY 0.340426 (-4220 1932);
PAINT SKYBLUE (-4220 1932);
DISPLAY INVISIBLE (-4220 1932);
FORCEPROP 2 LAST BOM_COST MEM
J 0
(-4175 1980);
PAINT ORANGE (-4175 1980);
DISPLAY INVISIBLE (-4175 1980);
FORCEPROP 2 LAST CDS_LIB mstr_symbols
J 0
(-4175 1975);
PAINT ORANGE (-4175 1975);
DISPLAY INVISIBLE (-4175 1975);
FORCEPROP 1 LAST BODY_TYPE PLUMBING
J 0
(-4220 1932);
DISPLAY 0.340426 (-4220 1932);
PAINT GREEN (-4220 1932);
DISPLAY INVISIBLE (-4220 1932);
FORCEPROP 1 LAST PATH I78
J 0
(-4125 2000);
DISPLAY 0.872340 (-4125 2000);
PAINT AQUA (-4125 2000);
DISPLAY INVISIBLE (-4125 2000);
FORCEPROP 2 LAST ROOM DDR4_GH_G
J 0
(-4175 2075);
DISPLAY 0.787234 (-4175 2075);
PAINT ORANGE (-4175 2075);
DISPLAY INVISIBLE (-4175 2075);
FORCEPROP 1 LAST HDL_POWER PVDDQ_GHJ
J 1
(-4175 2025);
DISPLAY 0.872340 (-4175 2025);
PAINT GREEN (-4175 2025);
DISPLAY INVISIBLE (-4175 2025);
FORCEADD PVTT_GHJ..1
(-3925 2150);
FORCEPROP 3 LASTPIN (-3925 2100) SIG_NAME PVTT_GHJ\g
J 0
(-3915 2110);
DISPLAY 0.659574 (-3915 2110);
PAINT MONO (-3915 2110);
DISPLAY INVISIBLE (-3915 2110);
FORCEPROP 1 LAST VOLTAGE 0.6V
J 0
(-3970 2107);
DISPLAY 0.340426 (-3970 2107);
PAINT SKYBLUE (-3970 2107);
DISPLAY INVISIBLE (-3970 2107);
FORCEPROP 2 LAST BOM_COST MEM
J 0
(-3925 2155);
PAINT ORANGE (-3925 2155);
DISPLAY INVISIBLE (-3925 2155);
FORCEPROP 2 LAST CDS_LIB mstr_symbols
J 0
(-3925 2150);
PAINT ORANGE (-3925 2150);
DISPLAY INVISIBLE (-3925 2150);
FORCEPROP 1 LAST BODY_TYPE PLUMBING
J 0
(-3970 2107);
DISPLAY 0.340426 (-3970 2107);
PAINT GREEN (-3970 2107);
DISPLAY INVISIBLE (-3970 2107);
FORCEPROP 1 LAST PATH I79
J 0
(-3875 2175);
DISPLAY 0.872340 (-3875 2175);
PAINT AQUA (-3875 2175);
DISPLAY INVISIBLE (-3875 2175);
FORCEPROP 2 LAST ROOM DDR4_GH_G
J 0
(-3925 2250);
DISPLAY 0.787234 (-3925 2250);
PAINT ORANGE (-3925 2250);
DISPLAY INVISIBLE (-3925 2250);
FORCEPROP 1 LAST HDL_POWER PVTT_GHJ
J 1
(-3925 2200);
DISPLAY 0.872340 (-3925 2200);
PAINT GREEN (-3925 2200);
DISPLAY INVISIBLE (-3925 2200);
FORCEADD PVPP_GHJ..1
(-7825 1700);
FORCEPROP 3 LASTPIN (-7825 1650) SIG_NAME PVPP_GHJ\g
J 0
(-7815 1660);
DISPLAY 0.659574 (-7815 1660);
PAINT MONO (-7815 1660);
DISPLAY INVISIBLE (-7815 1660);
FORCEPROP 1 LAST VOLTAGE 2.5V
J 0
(-7870 1657);
DISPLAY 0.340426 (-7870 1657);
PAINT SKYBLUE (-7870 1657);
DISPLAY INVISIBLE (-7870 1657);
FORCEPROP 0 LAST BOM_COST MEM
J 0
(-7825 1800);
PAINT ORANGE (-7825 1800);
DISPLAY INVISIBLE (-7825 1800);
FORCEPROP 2 LAST CDS_LIB mstr_symbols
J 0
(-7825 1700);
PAINT ORANGE (-7825 1700);
DISPLAY INVISIBLE (-7825 1700);
FORCEPROP 1 LAST BODY_TYPE PLUMBING
J 0
(-7870 1657);
DISPLAY 0.340426 (-7870 1657);
PAINT GREEN (-7870 1657);
DISPLAY INVISIBLE (-7870 1657);
FORCEPROP 1 LAST PATH I8
J 0
(-7775 1725);
DISPLAY 0.872340 (-7775 1725);
PAINT AQUA (-7775 1725);
DISPLAY INVISIBLE (-7775 1725);
FORCEPROP 2 LAST ROOM DDR4_GH_G
J 0
(-7825 1800);
PAINT ORANGE (-7825 1800);
DISPLAY INVISIBLE (-7825 1800);
FORCEPROP 1 LAST HDL_POWER PVPP_GHJ
J 1
(-7825 1750);
DISPLAY 0.872340 (-7825 1750);
PAINT GREEN (-7825 1750);
DISPLAY INVISIBLE (-7825 1750);
FORCEADD PVPP_GHJ..1
(-3775 2450);
FORCEPROP 3 LASTPIN (-3775 2400) SIG_NAME PVPP_GHJ\g
J 0
(-3765 2410);
DISPLAY 0.659574 (-3765 2410);
PAINT MONO (-3765 2410);
DISPLAY INVISIBLE (-3765 2410);
FORCEPROP 1 LAST VOLTAGE 2.5V
J 0
(-3820 2407);
DISPLAY 0.340426 (-3820 2407);
PAINT SKYBLUE (-3820 2407);
DISPLAY INVISIBLE (-3820 2407);
FORCEPROP 0 LAST BOM_COST MEM
J 0
(-3775 2550);
PAINT ORANGE (-3775 2550);
DISPLAY INVISIBLE (-3775 2550);
FORCEPROP 2 LAST CDS_LIB mstr_symbols
J 0
(-3775 2450);
PAINT ORANGE (-3775 2450);
DISPLAY INVISIBLE (-3775 2450);
FORCEPROP 1 LAST BODY_TYPE PLUMBING
J 0
(-3820 2407);
DISPLAY 0.340426 (-3820 2407);
PAINT GREEN (-3820 2407);
DISPLAY INVISIBLE (-3820 2407);
FORCEPROP 1 LAST PATH I80
J 0
(-3725 2475);
DISPLAY 0.872340 (-3725 2475);
PAINT AQUA (-3725 2475);
DISPLAY INVISIBLE (-3725 2475);
FORCEPROP 2 LAST ROOM DDR4_GH_G
J 0
(-3775 2550);
PAINT ORANGE (-3775 2550);
DISPLAY INVISIBLE (-3775 2550);
FORCEPROP 1 LAST HDL_POWER PVPP_GHJ
J 1
(-3775 2500);
DISPLAY 0.872340 (-3775 2500);
PAINT GREEN (-3775 2500);
DISPLAY INVISIBLE (-3775 2500);
FORCEADD TAP..6
R 2
(-4475 2550);
FORCEPROP 3 LASTPIN (-4525 2550) SIG_NAME M_H_DQ<27>
J 0
(-4515 2560);
DISPLAY 0.659574 (-4515 2560);
PAINT MONO (-4515 2560);
DISPLAY INVISIBLE (-4515 2560);
FORCEPROP 1 LASTPIN (-4525 2550) BN 27
J 2
(-4475 2560);
DISPLAY 0.617021 (-4475 2560);
PAINT PINK (-4475 2560);
FORCEPROP 2 LAST CDS_LIB mstr_standard
J 2
(-4475 2550);
DISPLAY 0.787234 (-4475 2550);
PAINT MONO (-4475 2550);
DISPLAY INVISIBLE (-4475 2550);
FORCEPROP 1 LAST BODY_TYPE PLUMBING
J 2
(-4475 2500);
DISPLAY 1.234043 (-4475 2500);
PAINT GREEN (-4475 2500);
DISPLAY INVISIBLE (-4475 2500);
FORCEPROP 1 LAST HDL_TAP TRUE
J 2
(-4800 2425);
DISPLAY 1.234043 (-4800 2425);
PAINT GREEN (-4800 2425);
DISPLAY INVISIBLE (-4800 2425);
FORCEPROP 1 LAST PATH I81
J 2
(-4473 2550);
DISPLAY 0.872340 (-4473 2550);
PAINT GREEN (-4473 2550);
DISPLAY INVISIBLE (-4473 2550);
FORCEADD TAP..6
R 2
(-4475 2600);
FORCEPROP 3 LASTPIN (-4525 2600) SIG_NAME M_H_DQ<28>
J 0
(-4515 2610);
DISPLAY 0.659574 (-4515 2610);
PAINT MONO (-4515 2610);
DISPLAY INVISIBLE (-4515 2610);
FORCEPROP 1 LASTPIN (-4525 2600) BN 28
J 2
(-4475 2610);
DISPLAY 0.617021 (-4475 2610);
PAINT PINK (-4475 2610);
FORCEPROP 2 LAST CDS_LIB mstr_standard
J 2
(-4475 2600);
DISPLAY 0.787234 (-4475 2600);
PAINT MONO (-4475 2600);
DISPLAY INVISIBLE (-4475 2600);
FORCEPROP 1 LAST BODY_TYPE PLUMBING
J 2
(-4475 2550);
DISPLAY 1.234043 (-4475 2550);
PAINT GREEN (-4475 2550);
DISPLAY INVISIBLE (-4475 2550);
FORCEPROP 1 LAST HDL_TAP TRUE
J 2
(-4800 2475);
DISPLAY 1.234043 (-4800 2475);
PAINT GREEN (-4800 2475);
DISPLAY INVISIBLE (-4800 2475);
FORCEPROP 1 LAST PATH I82
J 2
(-4473 2600);
DISPLAY 0.872340 (-4473 2600);
PAINT GREEN (-4473 2600);
DISPLAY INVISIBLE (-4473 2600);
FORCEADD TAP..6
R 2
(-4475 2650);
FORCEPROP 3 LASTPIN (-4525 2650) SIG_NAME M_H_DQ<29>
J 0
(-4515 2660);
DISPLAY 0.659574 (-4515 2660);
PAINT MONO (-4515 2660);
DISPLAY INVISIBLE (-4515 2660);
FORCEPROP 1 LASTPIN (-4525 2650) BN 29
J 2
(-4475 2660);
DISPLAY 0.617021 (-4475 2660);
PAINT PINK (-4475 2660);
FORCEPROP 2 LAST CDS_LIB mstr_standard
J 2
(-4475 2650);
DISPLAY 0.787234 (-4475 2650);
PAINT MONO (-4475 2650);
DISPLAY INVISIBLE (-4475 2650);
FORCEPROP 1 LAST BODY_TYPE PLUMBING
J 2
(-4475 2600);
DISPLAY 1.234043 (-4475 2600);
PAINT GREEN (-4475 2600);
DISPLAY INVISIBLE (-4475 2600);
FORCEPROP 1 LAST HDL_TAP TRUE
J 2
(-4800 2525);
DISPLAY 1.234043 (-4800 2525);
PAINT GREEN (-4800 2525);
DISPLAY INVISIBLE (-4800 2525);
FORCEPROP 1 LAST PATH I83
J 2
(-4473 2650);
DISPLAY 0.872340 (-4473 2650);
PAINT GREEN (-4473 2650);
DISPLAY INVISIBLE (-4473 2650);
FORCEADD TAP..6
R 2
(-4475 2750);
FORCEPROP 3 LASTPIN (-4525 2750) SIG_NAME M_H_DQ<31>
J 0
(-4515 2760);
DISPLAY 0.659574 (-4515 2760);
PAINT MONO (-4515 2760);
DISPLAY INVISIBLE (-4515 2760);
FORCEPROP 1 LASTPIN (-4525 2750) BN 31
J 2
(-4475 2760);
DISPLAY 0.617021 (-4475 2760);
PAINT PINK (-4475 2760);
FORCEPROP 2 LAST CDS_LIB mstr_standard
J 2
(-4475 2750);
DISPLAY 0.787234 (-4475 2750);
PAINT MONO (-4475 2750);
DISPLAY INVISIBLE (-4475 2750);
FORCEPROP 1 LAST BODY_TYPE PLUMBING
J 2
(-4475 2700);
DISPLAY 1.234043 (-4475 2700);
PAINT GREEN (-4475 2700);
DISPLAY INVISIBLE (-4475 2700);
FORCEPROP 1 LAST HDL_TAP TRUE
J 2
(-4800 2625);
DISPLAY 1.234043 (-4800 2625);
PAINT GREEN (-4800 2625);
DISPLAY INVISIBLE (-4800 2625);
FORCEPROP 1 LAST PATH I84
J 2
(-4473 2750);
DISPLAY 0.872340 (-4473 2750);
PAINT GREEN (-4473 2750);
DISPLAY INVISIBLE (-4473 2750);
FORCEADD TAP..6
R 2
(-4475 2700);
FORCEPROP 3 LASTPIN (-4525 2700) SIG_NAME M_H_DQ<30>
J 0
(-4515 2710);
DISPLAY 0.659574 (-4515 2710);
PAINT MONO (-4515 2710);
DISPLAY INVISIBLE (-4515 2710);
FORCEPROP 1 LASTPIN (-4525 2700) BN 30
J 2
(-4475 2710);
DISPLAY 0.617021 (-4475 2710);
PAINT PINK (-4475 2710);
FORCEPROP 2 LAST CDS_LIB mstr_standard
J 2
(-4475 2700);
DISPLAY 0.787234 (-4475 2700);
PAINT MONO (-4475 2700);
DISPLAY INVISIBLE (-4475 2700);
FORCEPROP 1 LAST BODY_TYPE PLUMBING
J 2
(-4475 2650);
DISPLAY 1.234043 (-4475 2650);
PAINT GREEN (-4475 2650);
DISPLAY INVISIBLE (-4475 2650);
FORCEPROP 1 LAST HDL_TAP TRUE
J 2
(-4800 2575);
DISPLAY 1.234043 (-4800 2575);
PAINT GREEN (-4800 2575);
DISPLAY INVISIBLE (-4800 2575);
FORCEPROP 1 LAST PATH I85
J 2
(-4473 2700);
DISPLAY 0.872340 (-4473 2700);
PAINT GREEN (-4473 2700);
DISPLAY INVISIBLE (-4473 2700);
FORCEADD TAP..6
R 2
(-4475 2850);
FORCEPROP 3 LASTPIN (-4525 2850) SIG_NAME M_H_DQ<33>
J 0
(-4515 2860);
DISPLAY 0.659574 (-4515 2860);
PAINT MONO (-4515 2860);
DISPLAY INVISIBLE (-4515 2860);
FORCEPROP 1 LASTPIN (-4525 2850) BN 33
J 2
(-4475 2860);
DISPLAY 0.617021 (-4475 2860);
PAINT PINK (-4475 2860);
FORCEPROP 2 LAST CDS_LIB mstr_standard
J 2
(-4475 2850);
DISPLAY 0.787234 (-4475 2850);
PAINT MONO (-4475 2850);
DISPLAY INVISIBLE (-4475 2850);
FORCEPROP 1 LAST BODY_TYPE PLUMBING
J 2
(-4475 2800);
DISPLAY 1.234043 (-4475 2800);
PAINT GREEN (-4475 2800);
DISPLAY INVISIBLE (-4475 2800);
FORCEPROP 1 LAST HDL_TAP TRUE
J 2
(-4800 2725);
DISPLAY 1.234043 (-4800 2725);
PAINT GREEN (-4800 2725);
DISPLAY INVISIBLE (-4800 2725);
FORCEPROP 1 LAST PATH I86
J 2
(-4473 2850);
DISPLAY 0.872340 (-4473 2850);
PAINT GREEN (-4473 2850);
DISPLAY INVISIBLE (-4473 2850);
FORCEADD TAP..6
R 2
(-4475 2800);
FORCEPROP 3 LASTPIN (-4525 2800) SIG_NAME M_H_DQ<32>
J 0
(-4515 2810);
DISPLAY 0.659574 (-4515 2810);
PAINT MONO (-4515 2810);
DISPLAY INVISIBLE (-4515 2810);
FORCEPROP 1 LASTPIN (-4525 2800) BN 32
J 2
(-4475 2810);
DISPLAY 0.617021 (-4475 2810);
PAINT PINK (-4475 2810);
FORCEPROP 2 LAST CDS_LIB mstr_standard
J 2
(-4475 2800);
DISPLAY 0.787234 (-4475 2800);
PAINT MONO (-4475 2800);
DISPLAY INVISIBLE (-4475 2800);
FORCEPROP 1 LAST BODY_TYPE PLUMBING
J 2
(-4475 2750);
DISPLAY 1.234043 (-4475 2750);
PAINT GREEN (-4475 2750);
DISPLAY INVISIBLE (-4475 2750);
FORCEPROP 1 LAST HDL_TAP TRUE
J 2
(-4800 2675);
DISPLAY 1.234043 (-4800 2675);
PAINT GREEN (-4800 2675);
DISPLAY INVISIBLE (-4800 2675);
FORCEPROP 1 LAST PATH I87
J 2
(-4473 2800);
DISPLAY 0.872340 (-4473 2800);
PAINT GREEN (-4473 2800);
DISPLAY INVISIBLE (-4473 2800);
FORCEADD TAP..6
R 2
(-4475 2900);
FORCEPROP 3 LASTPIN (-4525 2900) SIG_NAME M_H_DQ<34>
J 0
(-4515 2910);
DISPLAY 0.659574 (-4515 2910);
PAINT MONO (-4515 2910);
DISPLAY INVISIBLE (-4515 2910);
FORCEPROP 1 LASTPIN (-4525 2900) BN 34
J 2
(-4475 2910);
DISPLAY 0.617021 (-4475 2910);
PAINT PINK (-4475 2910);
FORCEPROP 2 LAST CDS_LIB mstr_standard
J 2
(-4475 2900);
DISPLAY 0.787234 (-4475 2900);
PAINT MONO (-4475 2900);
DISPLAY INVISIBLE (-4475 2900);
FORCEPROP 1 LAST BODY_TYPE PLUMBING
J 2
(-4475 2850);
DISPLAY 1.234043 (-4475 2850);
PAINT GREEN (-4475 2850);
DISPLAY INVISIBLE (-4475 2850);
FORCEPROP 1 LAST HDL_TAP TRUE
J 2
(-4800 2775);
DISPLAY 1.234043 (-4800 2775);
PAINT GREEN (-4800 2775);
DISPLAY INVISIBLE (-4800 2775);
FORCEPROP 1 LAST PATH I88
J 2
(-4473 2900);
DISPLAY 0.872340 (-4473 2900);
PAINT GREEN (-4473 2900);
DISPLAY INVISIBLE (-4473 2900);
FORCEADD TAP..6
R 2
(-4475 3000);
FORCEPROP 3 LASTPIN (-4525 3000) SIG_NAME M_H_DQ<36>
J 0
(-4515 3010);
DISPLAY 0.659574 (-4515 3010);
PAINT MONO (-4515 3010);
DISPLAY INVISIBLE (-4515 3010);
FORCEPROP 1 LASTPIN (-4525 3000) BN 36
J 2
(-4475 3010);
DISPLAY 0.617021 (-4475 3010);
PAINT PINK (-4475 3010);
FORCEPROP 2 LAST CDS_LIB mstr_standard
J 2
(-4475 3000);
DISPLAY 0.787234 (-4475 3000);
PAINT MONO (-4475 3000);
DISPLAY INVISIBLE (-4475 3000);
FORCEPROP 1 LAST BODY_TYPE PLUMBING
J 2
(-4475 2950);
DISPLAY 1.234043 (-4475 2950);
PAINT GREEN (-4475 2950);
DISPLAY INVISIBLE (-4475 2950);
FORCEPROP 1 LAST HDL_TAP TRUE
J 2
(-4800 2875);
DISPLAY 1.234043 (-4800 2875);
PAINT GREEN (-4800 2875);
DISPLAY INVISIBLE (-4800 2875);
FORCEPROP 1 LAST PATH I89
J 2
(-4473 3000);
DISPLAY 0.872340 (-4473 3000);
PAINT GREEN (-4473 3000);
DISPLAY INVISIBLE (-4473 3000);
FORCEADD OFFPAGE..5
(-6650 1700);
FORCEPROP 2 LAST $XR1 58 
J 0
(-6964 1700);
DISPLAY 0.638298 (-6964 1700);
PAINT MONO (-6964 1700);
FORCEPROP 2 LAST $XR0 79 
J 0
(-6874 1700);
DISPLAY 0.638298 (-6874 1700);
PAINT MONO (-6874 1700);
FORCEPROP 2 LAST CDS_LIB mstr_standard
J 0
(-6650 1700);
DISPLAY 0.787234 (-6650 1700);
PAINT MONO (-6650 1700);
DISPLAY INVISIBLE (-6650 1700);
FORCEPROP 1 LAST OFFPAGE TRUE
J 0
(-6325 1575);
DISPLAY 1.404255 (-6325 1575);
PAINT GREEN (-6325 1575);
DISPLAY INVISIBLE (-6325 1575);
FORCEPROP 1 LAST COMMENT_BODY TRUE
J 0
(-6550 1625);
DISPLAY 1.404255 (-6550 1625);
PAINT GREEN (-6550 1625);
DISPLAY INVISIBLE (-6550 1625);
FORCEPROP 2 LAST PATH I9
J 0
(-6850 1750);
DISPLAY 1.021277 (-6850 1750);
PAINT ORANGE (-6850 1750);
DISPLAY INVISIBLE (-6850 1750);
FORCEADD TAP..6
R 2
(-4475 2950);
FORCEPROP 3 LASTPIN (-4525 2950) SIG_NAME M_H_DQ<35>
J 0
(-4515 2960);
DISPLAY 0.659574 (-4515 2960);
PAINT MONO (-4515 2960);
DISPLAY INVISIBLE (-4515 2960);
FORCEPROP 1 LASTPIN (-4525 2950) BN 35
J 2
(-4475 2960);
DISPLAY 0.617021 (-4475 2960);
PAINT PINK (-4475 2960);
FORCEPROP 2 LAST CDS_LIB mstr_standard
J 2
(-4475 2950);
DISPLAY 0.787234 (-4475 2950);
PAINT MONO (-4475 2950);
DISPLAY INVISIBLE (-4475 2950);
FORCEPROP 1 LAST BODY_TYPE PLUMBING
J 2
(-4475 2900);
DISPLAY 1.234043 (-4475 2900);
PAINT GREEN (-4475 2900);
DISPLAY INVISIBLE (-4475 2900);
FORCEPROP 1 LAST HDL_TAP TRUE
J 2
(-4800 2825);
DISPLAY 1.234043 (-4800 2825);
PAINT GREEN (-4800 2825);
DISPLAY INVISIBLE (-4800 2825);
FORCEPROP 1 LAST PATH I90
J 2
(-4473 2950);
DISPLAY 0.872340 (-4473 2950);
PAINT GREEN (-4473 2950);
DISPLAY INVISIBLE (-4473 2950);
FORCEADD TAP..6
R 2
(-4475 3100);
FORCEPROP 3 LASTPIN (-4525 3100) SIG_NAME M_H_DQ<38>
J 0
(-4515 3110);
DISPLAY 0.659574 (-4515 3110);
PAINT MONO (-4515 3110);
DISPLAY INVISIBLE (-4515 3110);
FORCEPROP 1 LASTPIN (-4525 3100) BN 38
J 2
(-4475 3110);
DISPLAY 0.617021 (-4475 3110);
PAINT PINK (-4475 3110);
FORCEPROP 2 LAST CDS_LIB mstr_standard
J 2
(-4475 3100);
DISPLAY 0.787234 (-4475 3100);
PAINT MONO (-4475 3100);
DISPLAY INVISIBLE (-4475 3100);
FORCEPROP 1 LAST BODY_TYPE PLUMBING
J 2
(-4475 3050);
DISPLAY 1.234043 (-4475 3050);
PAINT GREEN (-4475 3050);
DISPLAY INVISIBLE (-4475 3050);
FORCEPROP 1 LAST HDL_TAP TRUE
J 2
(-4800 2975);
DISPLAY 1.234043 (-4800 2975);
PAINT GREEN (-4800 2975);
DISPLAY INVISIBLE (-4800 2975);
FORCEPROP 1 LAST PATH I91
J 2
(-4473 3100);
DISPLAY 0.872340 (-4473 3100);
PAINT GREEN (-4473 3100);
DISPLAY INVISIBLE (-4473 3100);
FORCEADD TAP..6
R 2
(-4475 3050);
FORCEPROP 3 LASTPIN (-4525 3050) SIG_NAME M_H_DQ<37>
J 0
(-4515 3060);
DISPLAY 0.659574 (-4515 3060);
PAINT MONO (-4515 3060);
DISPLAY INVISIBLE (-4515 3060);
FORCEPROP 1 LASTPIN (-4525 3050) BN 37
J 2
(-4475 3060);
DISPLAY 0.617021 (-4475 3060);
PAINT PINK (-4475 3060);
FORCEPROP 2 LAST CDS_LIB mstr_standard
J 2
(-4475 3050);
DISPLAY 0.787234 (-4475 3050);
PAINT MONO (-4475 3050);
DISPLAY INVISIBLE (-4475 3050);
FORCEPROP 1 LAST BODY_TYPE PLUMBING
J 2
(-4475 3000);
DISPLAY 1.234043 (-4475 3000);
PAINT GREEN (-4475 3000);
DISPLAY INVISIBLE (-4475 3000);
FORCEPROP 1 LAST HDL_TAP TRUE
J 2
(-4800 2925);
DISPLAY 1.234043 (-4800 2925);
PAINT GREEN (-4800 2925);
DISPLAY INVISIBLE (-4800 2925);
FORCEPROP 1 LAST PATH I92
J 2
(-4473 3050);
DISPLAY 0.872340 (-4473 3050);
PAINT GREEN (-4473 3050);
DISPLAY INVISIBLE (-4473 3050);
FORCEADD TAP..6
R 2
(-4475 3150);
FORCEPROP 3 LASTPIN (-4525 3150) SIG_NAME M_H_DQ<39>
J 0
(-4515 3160);
DISPLAY 0.659574 (-4515 3160);
PAINT MONO (-4515 3160);
DISPLAY INVISIBLE (-4515 3160);
FORCEPROP 1 LASTPIN (-4525 3150) BN 39
J 2
(-4475 3160);
DISPLAY 0.617021 (-4475 3160);
PAINT PINK (-4475 3160);
FORCEPROP 2 LAST CDS_LIB mstr_standard
J 2
(-4475 3150);
DISPLAY 0.787234 (-4475 3150);
PAINT MONO (-4475 3150);
DISPLAY INVISIBLE (-4475 3150);
FORCEPROP 1 LAST BODY_TYPE PLUMBING
J 2
(-4475 3100);
DISPLAY 1.234043 (-4475 3100);
PAINT GREEN (-4475 3100);
DISPLAY INVISIBLE (-4475 3100);
FORCEPROP 1 LAST HDL_TAP TRUE
J 2
(-4800 3025);
DISPLAY 1.234043 (-4800 3025);
PAINT GREEN (-4800 3025);
DISPLAY INVISIBLE (-4800 3025);
FORCEPROP 1 LAST PATH I93
J 2
(-4473 3150);
DISPLAY 0.872340 (-4473 3150);
PAINT GREEN (-4473 3150);
DISPLAY INVISIBLE (-4473 3150);
FORCEADD TAP..6
R 2
(-4475 3250);
FORCEPROP 3 LASTPIN (-4525 3250) SIG_NAME M_H_DQ<41>
J 0
(-4515 3260);
DISPLAY 0.659574 (-4515 3260);
PAINT MONO (-4515 3260);
DISPLAY INVISIBLE (-4515 3260);
FORCEPROP 1 LASTPIN (-4525 3250) BN 41
J 2
(-4475 3260);
DISPLAY 0.617021 (-4475 3260);
PAINT PINK (-4475 3260);
FORCEPROP 2 LAST CDS_LIB mstr_standard
J 2
(-4475 3250);
DISPLAY 0.787234 (-4475 3250);
PAINT MONO (-4475 3250);
DISPLAY INVISIBLE (-4475 3250);
FORCEPROP 1 LAST BODY_TYPE PLUMBING
J 2
(-4475 3200);
DISPLAY 1.234043 (-4475 3200);
PAINT GREEN (-4475 3200);
DISPLAY INVISIBLE (-4475 3200);
FORCEPROP 1 LAST HDL_TAP TRUE
J 2
(-4800 3125);
DISPLAY 1.234043 (-4800 3125);
PAINT GREEN (-4800 3125);
DISPLAY INVISIBLE (-4800 3125);
FORCEPROP 1 LAST PATH I94
J 2
(-4473 3250);
DISPLAY 0.872340 (-4473 3250);
PAINT GREEN (-4473 3250);
DISPLAY INVISIBLE (-4473 3250);
FORCEADD TAP..6
R 2
(-4475 3200);
FORCEPROP 3 LASTPIN (-4525 3200) SIG_NAME M_H_DQ<40>
J 0
(-4515 3210);
DISPLAY 0.659574 (-4515 3210);
PAINT MONO (-4515 3210);
DISPLAY INVISIBLE (-4515 3210);
FORCEPROP 1 LASTPIN (-4525 3200) BN 40
J 2
(-4475 3210);
DISPLAY 0.617021 (-4475 3210);
PAINT PINK (-4475 3210);
FORCEPROP 2 LAST CDS_LIB mstr_standard
J 2
(-4475 3200);
DISPLAY 0.787234 (-4475 3200);
PAINT MONO (-4475 3200);
DISPLAY INVISIBLE (-4475 3200);
FORCEPROP 1 LAST BODY_TYPE PLUMBING
J 2
(-4475 3150);
DISPLAY 1.234043 (-4475 3150);
PAINT GREEN (-4475 3150);
DISPLAY INVISIBLE (-4475 3150);
FORCEPROP 1 LAST HDL_TAP TRUE
J 2
(-4800 3075);
DISPLAY 1.234043 (-4800 3075);
PAINT GREEN (-4800 3075);
DISPLAY INVISIBLE (-4800 3075);
FORCEPROP 1 LAST PATH I95
J 2
(-4473 3200);
DISPLAY 0.872340 (-4473 3200);
PAINT GREEN (-4473 3200);
DISPLAY INVISIBLE (-4473 3200);
FORCEADD TAP..6
R 2
(-4475 3350);
FORCEPROP 3 LASTPIN (-4525 3350) SIG_NAME M_H_DQ<43>
J 0
(-4515 3360);
DISPLAY 0.659574 (-4515 3360);
PAINT MONO (-4515 3360);
DISPLAY INVISIBLE (-4515 3360);
FORCEPROP 1 LASTPIN (-4525 3350) BN 43
J 2
(-4475 3360);
DISPLAY 0.617021 (-4475 3360);
PAINT PINK (-4475 3360);
FORCEPROP 2 LAST CDS_LIB mstr_standard
J 2
(-4475 3350);
DISPLAY 0.787234 (-4475 3350);
PAINT MONO (-4475 3350);
DISPLAY INVISIBLE (-4475 3350);
FORCEPROP 1 LAST BODY_TYPE PLUMBING
J 2
(-4475 3300);
DISPLAY 1.234043 (-4475 3300);
PAINT GREEN (-4475 3300);
DISPLAY INVISIBLE (-4475 3300);
FORCEPROP 1 LAST HDL_TAP TRUE
J 2
(-4800 3225);
DISPLAY 1.234043 (-4800 3225);
PAINT GREEN (-4800 3225);
DISPLAY INVISIBLE (-4800 3225);
FORCEPROP 1 LAST PATH I96
J 2
(-4473 3350);
DISPLAY 0.872340 (-4473 3350);
PAINT GREEN (-4473 3350);
DISPLAY INVISIBLE (-4473 3350);
FORCEADD TAP..6
R 2
(-4475 3300);
FORCEPROP 3 LASTPIN (-4525 3300) SIG_NAME M_H_DQ<42>
J 0
(-4515 3310);
DISPLAY 0.659574 (-4515 3310);
PAINT MONO (-4515 3310);
DISPLAY INVISIBLE (-4515 3310);
FORCEPROP 1 LASTPIN (-4525 3300) BN 42
J 2
(-4475 3310);
DISPLAY 0.617021 (-4475 3310);
PAINT PINK (-4475 3310);
FORCEPROP 2 LAST CDS_LIB mstr_standard
J 2
(-4475 3300);
DISPLAY 0.787234 (-4475 3300);
PAINT MONO (-4475 3300);
DISPLAY INVISIBLE (-4475 3300);
FORCEPROP 1 LAST BODY_TYPE PLUMBING
J 2
(-4475 3250);
DISPLAY 1.234043 (-4475 3250);
PAINT GREEN (-4475 3250);
DISPLAY INVISIBLE (-4475 3250);
FORCEPROP 1 LAST HDL_TAP TRUE
J 2
(-4800 3175);
DISPLAY 1.234043 (-4800 3175);
PAINT GREEN (-4800 3175);
DISPLAY INVISIBLE (-4800 3175);
FORCEPROP 1 LAST PATH I97
J 2
(-4473 3300);
DISPLAY 0.872340 (-4473 3300);
PAINT GREEN (-4473 3300);
DISPLAY INVISIBLE (-4473 3300);
FORCEADD TAP..6
R 2
(-4475 3400);
FORCEPROP 3 LASTPIN (-4525 3400) SIG_NAME M_H_DQ<44>
J 0
(-4515 3410);
DISPLAY 0.659574 (-4515 3410);
PAINT MONO (-4515 3410);
DISPLAY INVISIBLE (-4515 3410);
FORCEPROP 1 LASTPIN (-4525 3400) BN 44
J 2
(-4475 3410);
DISPLAY 0.617021 (-4475 3410);
PAINT PINK (-4475 3410);
FORCEPROP 2 LAST CDS_LIB mstr_standard
J 2
(-4475 3400);
DISPLAY 0.787234 (-4475 3400);
PAINT MONO (-4475 3400);
DISPLAY INVISIBLE (-4475 3400);
FORCEPROP 1 LAST BODY_TYPE PLUMBING
J 2
(-4475 3350);
DISPLAY 1.234043 (-4475 3350);
PAINT GREEN (-4475 3350);
DISPLAY INVISIBLE (-4475 3350);
FORCEPROP 1 LAST HDL_TAP TRUE
J 2
(-4800 3275);
DISPLAY 1.234043 (-4800 3275);
PAINT GREEN (-4800 3275);
DISPLAY INVISIBLE (-4800 3275);
FORCEPROP 1 LAST PATH I98
J 2
(-4473 3400);
DISPLAY 0.872340 (-4473 3400);
PAINT GREEN (-4473 3400);
DISPLAY INVISIBLE (-4473 3400);
FORCEADD TAP..6
R 2
(-4475 3500);
FORCEPROP 3 LASTPIN (-4525 3500) SIG_NAME M_H_DQ<46>
J 0
(-4515 3510);
DISPLAY 0.659574 (-4515 3510);
PAINT MONO (-4515 3510);
DISPLAY INVISIBLE (-4515 3510);
FORCEPROP 1 LASTPIN (-4525 3500) BN 46
J 2
(-4475 3510);
DISPLAY 0.617021 (-4475 3510);
PAINT PINK (-4475 3510);
FORCEPROP 2 LAST CDS_LIB mstr_standard
J 2
(-4475 3500);
DISPLAY 0.787234 (-4475 3500);
PAINT MONO (-4475 3500);
DISPLAY INVISIBLE (-4475 3500);
FORCEPROP 1 LAST BODY_TYPE PLUMBING
J 2
(-4475 3450);
DISPLAY 1.234043 (-4475 3450);
PAINT GREEN (-4475 3450);
DISPLAY INVISIBLE (-4475 3450);
FORCEPROP 1 LAST HDL_TAP TRUE
J 2
(-4800 3375);
DISPLAY 1.234043 (-4800 3375);
PAINT GREEN (-4800 3375);
DISPLAY INVISIBLE (-4800 3375);
FORCEPROP 1 LAST PATH I99
J 2
(-4473 3500);
DISPLAY 0.872340 (-4473 3500);
PAINT GREEN (-4473 3500);
DISPLAY INVISIBLE (-4473 3500);
FORCEADD INTEL_CORP_BPAGE..1
(0 0);
FORCEPROP 1 LAST CDS_CON_LAST_MODIFIED Fri Jun 16 17:48:29 2017
J 0
(-1425 325);
PAINT ORANGE (-1425 325);
DISPLAY INVISIBLE (-1425 325);
FORCEPROP 1 LAST CUSTOM_TXT_CDS <CURRENT_DESIGN_SHEET> OF <TOTAL_DESIGN_SHEETS>
J 0
(-500 25);
PAINT ORANGE (-500 25);
FORCEPROP 1 LAST CUSTOM_TXT_CDS <CON_LAST_MODIFIED>
J 0
(-4000 100);
PAINT ORANGE (-4000 100);
FORCEPROP 2 LAST CUSTOM_TXT_CDS <XR_PAGE_TITLE>
J 0
(-7890 5250);
DISPLAY 0.638298 (-7890 5250);
PAINT PINK (-7890 5250);
DISPLAY INVISIBLE (-7890 5250);
FORCEPROP 1 LAST SCH_TITLE CPU1 DDR4 CH H DIMM1
J 0
(-7950 50);
DISPLAY 1.212766 (-7950 50);
PAINT ORANGE (-7950 50);
FORCEPROP 2 LAST CDS_LIB mstr_symbols
J 0
(0 0);
PAINT ORANGE (0 0);
DISPLAY INVISIBLE (0 0);
FORCEPROP 2 LAST PAGE_BORDER TRUE
J 0
(-7890 5250);
DISPLAY 1.042553 (-7890 5250);
PAINT PINK (-7890 5250);
DISPLAY INVISIBLE (-7890 5250);
FORCEPROP 1 LAST COMMENT_BODY TRUE
J 0
(12 12);
DISPLAY 0.489362 (12 12);
PAINT GREEN (12 12);
DISPLAY INVISIBLE (12 12);
FORCEPROP 2 LAST CDS_XR_PAGE_TITLE CR-80 : @BASEBOARD_FAB2_LIB.BASEBOARD_FAB2(SCH_1):PAGE80
J 0
(-7890 5250);
DISPLAY 0.638298 (-7890 5250);
PAINT PINK (-7890 5250);
DISPLAY INVISIBLE (-7890 5250);
FORCEADD BOM_NOTE..1
(-7675 4750);
FORCEPROP 0 LAST L1 UNSTUFF FOR SKU B
J 0
(-7825 4650);
DISPLAY 1.063830 (-7825 4650);
PAINT WHITE (-7825 4650);
FORCEPROP 2 LAST BOM_COST SB
J 0
(-7825 4725);
DISPLAY 1.361702 (-7825 4725);
PAINT ORANGE (-7825 4725);
DISPLAY INVISIBLE (-7825 4725);
FORCEPROP 2 LAST CDS_LIB mstr_symbols
J 0
(-7675 4750);
PAINT ORANGE (-7675 4750);
DISPLAY INVISIBLE (-7675 4750);
FORCEPROP 1 LAST COMMENT_BODY TRUE
J 0
(-7650 4850);
DISPLAY 1.319149 (-7650 4850);
PAINT ORANGE (-7650 4850);
DISPLAY INVISIBLE (-7650 4850);
FORCEPROP 2 LAST ROOM SB_HEADERS
J 0
(-7825 4725);
DISPLAY 1.361702 (-7825 4725);
PAINT ORANGE (-7825 4725);
DISPLAY INVISIBLE (-7825 4725);
WIRE 16 -1 (-7825 1400)(-7825 1500);
WIRE 16 -1 (-7825 1500)(-5725 1500);
WIRE 16 -1 (-1575 600)(-1575 700);
WIRE 16 -1 (-1575 700)(-1575 750);
WIRE 16 -1 (-1575 700)(-1375 700);
WIRE 16 -1 (-1575 750)(-1575 800);
WIRE 16 -1 (-1575 750)(-1375 750);
WIRE 16 -1 (-1575 800)(-1575 850);
WIRE 16 -1 (-1575 800)(-1375 800);
WIRE 16 -1 (-1575 850)(-1575 900);
WIRE 16 -1 (-1575 850)(-1375 850);
WIRE 16 -1 (-1575 900)(-1575 950);
WIRE 16 -1 (-1575 900)(-1375 900);
WIRE 16 -1 (-1575 950)(-1575 1000);
WIRE 16 -1 (-1575 950)(-1375 950);
WIRE 16 -1 (-1575 1000)(-1575 1050);
WIRE 16 -1 (-1575 1000)(-1375 1000);
WIRE 16 -1 (-1575 1050)(-1575 1100);
WIRE 16 -1 (-1575 1050)(-1375 1050);
WIRE 16 -1 (-1575 1100)(-1575 1150);
WIRE 16 -1 (-1575 1100)(-1375 1100);
WIRE 16 -1 (-1575 1150)(-1575 1200);
WIRE 16 -1 (-1575 1150)(-1375 1150);
WIRE 16 -1 (-1575 1200)(-1575 1250);
WIRE 16 -1 (-1575 1200)(-1375 1200);
WIRE 16 -1 (-1575 1250)(-1575 1300);
WIRE 16 -1 (-1575 1250)(-1375 1250);
WIRE 16 -1 (-1575 1300)(-1575 1350);
WIRE 16 -1 (-1575 1300)(-1375 1300);
WIRE 16 -1 (-1575 1350)(-1575 1400);
WIRE 16 -1 (-1575 1350)(-1375 1350);
WIRE 16 -1 (-1575 1400)(-1575 1450);
WIRE 16 -1 (-1575 1400)(-1375 1400);
WIRE 16 -1 (-1575 1450)(-1575 1500);
WIRE 16 -1 (-1575 1450)(-1375 1450);
WIRE 16 -1 (-1575 1500)(-1575 1550);
WIRE 16 -1 (-1575 1500)(-1375 1500);
WIRE 16 -1 (-1575 1550)(-1575 1600);
WIRE 16 -1 (-1575 1550)(-1375 1550);
WIRE 16 -1 (-1575 1600)(-1575 1650);
WIRE 16 -1 (-1575 1600)(-1375 1600);
WIRE 16 -1 (-1575 1650)(-1575 1700);
WIRE 16 -1 (-1575 1650)(-1375 1650);
WIRE 16 -1 (-1575 1700)(-1575 1750);
WIRE 16 -1 (-1575 1700)(-1375 1700);
WIRE 16 -1 (-1575 1750)(-1575 1800);
WIRE 16 -1 (-1575 1750)(-1375 1750);
WIRE 16 -1 (-1575 1800)(-1575 1850);
WIRE 16 -1 (-1575 1800)(-1375 1800);
WIRE 16 -1 (-1575 1850)(-1575 1900);
WIRE 16 -1 (-1575 1850)(-1375 1850);
WIRE 16 -1 (-1575 1900)(-1575 1950);
WIRE 16 -1 (-1575 1900)(-1375 1900);
WIRE 16 -1 (-1575 1950)(-1575 2000);
WIRE 16 -1 (-1575 1950)(-1375 1950);
WIRE 16 -1 (-1575 2000)(-1575 2050);
WIRE 16 -1 (-1575 2000)(-1375 2000);
WIRE 16 -1 (-1575 2050)(-1575 2100);
WIRE 16 -1 (-1575 2050)(-1375 2050);
WIRE 16 -1 (-1575 2100)(-1575 2150);
WIRE 16 -1 (-1575 2100)(-1375 2100);
WIRE 16 -1 (-1575 2150)(-1575 2200);
WIRE 16 -1 (-1575 2150)(-1375 2150);
WIRE 16 -1 (-1575 2200)(-1575 2250);
WIRE 16 -1 (-1575 2200)(-1375 2200);
WIRE 16 -1 (-1575 2250)(-1575 2300);
WIRE 16 -1 (-1575 2250)(-1375 2250);
WIRE 16 -1 (-1575 2300)(-1575 2350);
WIRE 16 -1 (-1575 2300)(-1375 2300);
WIRE 16 -1 (-1575 2350)(-1575 2400);
WIRE 16 -1 (-1575 2350)(-1375 2350);
WIRE 16 -1 (-1575 2400)(-1575 2450);
WIRE 16 -1 (-1575 2400)(-1375 2400);
WIRE 16 -1 (-1575 2450)(-1575 2500);
WIRE 16 -1 (-1575 2450)(-1375 2450);
WIRE 16 -1 (-1575 2500)(-1575 2550);
WIRE 16 -1 (-1575 2500)(-1375 2500);
WIRE 16 -1 (-1575 2550)(-1575 2600);
WIRE 16 -1 (-1575 2550)(-1375 2550);
WIRE 16 -1 (-1575 2600)(-1575 2650);
WIRE 16 -1 (-1575 2600)(-1375 2600);
WIRE 16 -1 (-1575 2650)(-1575 2700);
WIRE 16 -1 (-1575 2650)(-1375 2650);
WIRE 16 -1 (-1575 2700)(-1575 2750);
WIRE 16 -1 (-1575 2700)(-1375 2700);
WIRE 16 -1 (-1575 2750)(-1575 2800);
WIRE 16 -1 (-1575 2750)(-1375 2750);
WIRE 16 -1 (-1575 2800)(-1575 2850);
WIRE 16 -1 (-1575 2800)(-1375 2800);
WIRE 16 -1 (-1575 2850)(-1575 2900);
WIRE 16 -1 (-1575 2850)(-1375 2850);
WIRE 16 -1 (-1575 2900)(-1575 2950);
WIRE 16 -1 (-1575 2900)(-1375 2900);
WIRE 16 -1 (-1575 2950)(-1575 3000);
WIRE 16 -1 (-1575 2950)(-1375 2950);
WIRE 16 -1 (-1575 3000)(-1375 3000);
WIRE 16 -1 (-175 600)(-175 700);
WIRE 16 -1 (-175 700)(-175 750);
WIRE 16 -1 (-175 700)(-375 700);
WIRE 16 -1 (-175 750)(-175 800);
WIRE 16 -1 (-175 750)(-375 750);
WIRE 16 -1 (-175 800)(-175 850);
WIRE 16 -1 (-175 800)(-375 800);
WIRE 16 -1 (-175 850)(-175 900);
WIRE 16 -1 (-175 850)(-375 850);
WIRE 16 -1 (-175 900)(-175 950);
WIRE 16 -1 (-175 900)(-375 900);
WIRE 16 -1 (-175 950)(-175 1000);
WIRE 16 -1 (-175 950)(-375 950);
WIRE 16 -1 (-175 1000)(-175 1050);
WIRE 16 -1 (-175 1000)(-375 1000);
WIRE 16 -1 (-175 1050)(-175 1100);
WIRE 16 -1 (-175 1050)(-375 1050);
WIRE 16 -1 (-175 1100)(-175 1150);
WIRE 16 -1 (-175 1100)(-375 1100);
WIRE 16 -1 (-175 1150)(-175 1200);
WIRE 16 -1 (-175 1150)(-375 1150);
WIRE 16 -1 (-175 1200)(-175 1250);
WIRE 16 -1 (-175 1200)(-375 1200);
WIRE 16 -1 (-175 1250)(-175 1300);
WIRE 16 -1 (-175 1250)(-375 1250);
WIRE 16 -1 (-175 1300)(-175 1350);
WIRE 16 -1 (-175 1300)(-375 1300);
WIRE 16 -1 (-175 1350)(-175 1400);
WIRE 16 -1 (-175 1350)(-375 1350);
WIRE 16 -1 (-175 1400)(-175 1450);
WIRE 16 -1 (-175 1400)(-375 1400);
WIRE 16 -1 (-175 1450)(-175 1500);
WIRE 16 -1 (-175 1450)(-375 1450);
WIRE 16 -1 (-175 1500)(-175 1550);
WIRE 16 -1 (-175 1500)(-375 1500);
WIRE 16 -1 (-175 1550)(-175 1600);
WIRE 16 -1 (-175 1550)(-375 1550);
WIRE 16 -1 (-175 1600)(-175 1650);
WIRE 16 -1 (-175 1600)(-375 1600);
WIRE 16 -1 (-175 1650)(-175 1700);
WIRE 16 -1 (-175 1650)(-375 1650);
WIRE 16 -1 (-175 1700)(-175 1750);
WIRE 16 -1 (-175 1700)(-375 1700);
WIRE 16 -1 (-175 1750)(-175 1800);
WIRE 16 -1 (-175 1750)(-375 1750);
WIRE 16 -1 (-175 1800)(-175 1850);
WIRE 16 -1 (-175 1800)(-375 1800);
WIRE 16 -1 (-175 1850)(-175 1900);
WIRE 16 -1 (-175 1850)(-375 1850);
WIRE 16 -1 (-175 1900)(-175 1950);
WIRE 16 -1 (-175 1900)(-375 1900);
WIRE 16 -1 (-175 1950)(-175 2000);
WIRE 16 -1 (-175 1950)(-375 1950);
WIRE 16 -1 (-175 2000)(-175 2050);
WIRE 16 -1 (-175 2000)(-375 2000);
WIRE 16 -1 (-175 2050)(-175 2100);
WIRE 16 -1 (-175 2050)(-375 2050);
WIRE 16 -1 (-175 2100)(-175 2150);
WIRE 16 -1 (-175 2100)(-375 2100);
WIRE 16 -1 (-175 2150)(-175 2200);
WIRE 16 -1 (-175 2150)(-375 2150);
WIRE 16 -1 (-175 2200)(-175 2250);
WIRE 16 -1 (-175 2200)(-375 2200);
WIRE 16 -1 (-175 2250)(-175 2300);
WIRE 16 -1 (-175 2250)(-375 2250);
WIRE 16 -1 (-175 2300)(-175 2350);
WIRE 16 -1 (-175 2300)(-375 2300);
WIRE 16 -1 (-175 2350)(-175 2400);
WIRE 16 -1 (-175 2350)(-375 2350);
WIRE 16 -1 (-175 2400)(-175 2450);
WIRE 16 -1 (-175 2400)(-375 2400);
WIRE 16 -1 (-175 2450)(-175 2500);
WIRE 16 -1 (-175 2450)(-375 2450);
WIRE 16 -1 (-175 2500)(-175 2550);
WIRE 16 -1 (-175 2500)(-375 2500);
WIRE 16 -1 (-175 2550)(-175 2600);
WIRE 16 -1 (-175 2550)(-375 2550);
WIRE 16 -1 (-175 2600)(-175 2650);
WIRE 16 -1 (-175 2600)(-375 2600);
WIRE 16 -1 (-175 2650)(-175 2700);
WIRE 16 -1 (-175 2650)(-375 2650);
WIRE 16 -1 (-175 2700)(-175 2750);
WIRE 16 -1 (-175 2700)(-375 2700);
WIRE 16 -1 (-175 2750)(-175 2800);
WIRE 16 -1 (-175 2750)(-375 2750);
WIRE 16 -1 (-175 2800)(-175 2850);
WIRE 16 -1 (-175 2800)(-375 2800);
WIRE 16 -1 (-175 2850)(-175 2900);
WIRE 16 -1 (-175 2850)(-375 2850);
WIRE 16 -1 (-175 2900)(-175 2950);
WIRE 16 -1 (-175 2900)(-375 2900);
WIRE 16 -1 (-175 2950)(-175 3000);
WIRE 16 -1 (-175 2950)(-375 2950);
WIRE 16 -1 (-175 3000)(-375 3000);
WIRE 16 -1 (-2375 2300)(-2375 2375);
WIRE 16 -1 (-2375 2250)(-2375 2300);
WIRE 16 -1 (-2575 2300)(-2375 2300);
WIRE 16 -1 (-2575 2250)(-2375 2250);
WIRE 16 -1 (-7225 900)(-7225 800);
WIRE 16 -1 (-4175 1925)(-4175 1850);
WIRE 16 -1 (-4175 1850)(-3775 1850);
WIRE 16 -1 (-3775 1800)(-3775 1850);
WIRE 16 -1 (-3775 1850)(-3575 1850);
WIRE 16 -1 (-3775 1750)(-3775 1800);
WIRE 16 -1 (-3775 1800)(-3575 1800);
WIRE 16 -1 (-3775 1700)(-3775 1750);
WIRE 16 -1 (-3775 1750)(-3575 1750);
WIRE 16 -1 (-3775 1650)(-3775 1700);
WIRE 16 -1 (-3775 1700)(-3575 1700);
WIRE 16 -1 (-3775 1600)(-3775 1650);
WIRE 16 -1 (-3775 1650)(-3575 1650);
WIRE 16 -1 (-3775 1550)(-3775 1600);
WIRE 16 -1 (-3775 1600)(-3575 1600);
WIRE 16 -1 (-3775 1500)(-3775 1550);
WIRE 16 -1 (-3775 1550)(-3575 1550);
WIRE 16 -1 (-3775 1450)(-3775 1500);
WIRE 16 -1 (-3775 1500)(-3575 1500);
WIRE 16 -1 (-3775 1400)(-3775 1450);
WIRE 16 -1 (-3775 1450)(-3575 1450);
WIRE 16 -1 (-3775 1350)(-3775 1400);
WIRE 16 -1 (-3775 1400)(-3575 1400);
WIRE 16 -1 (-3775 1300)(-3775 1350);
WIRE 16 -1 (-3775 1350)(-3575 1350);
WIRE 16 -1 (-3775 1250)(-3775 1300);
WIRE 16 -1 (-3775 1300)(-3575 1300);
WIRE 16 -1 (-3775 1200)(-3775 1250);
WIRE 16 -1 (-3775 1250)(-3575 1250);
WIRE 16 -1 (-3775 1150)(-3775 1200);
WIRE 16 -1 (-3775 1200)(-3575 1200);
WIRE 16 -1 (-3775 1100)(-3775 1150);
WIRE 16 -1 (-3775 1150)(-3575 1150);
WIRE 16 -1 (-3775 1050)(-3775 1100);
WIRE 16 -1 (-3775 1100)(-3575 1100);
WIRE 16 -1 (-3775 1000)(-3775 1050);
WIRE 16 -1 (-3775 1050)(-3575 1050);
WIRE 16 -1 (-3775 950)(-3775 1000);
WIRE 16 -1 (-3775 1000)(-3575 1000);
WIRE 16 -1 (-3775 900)(-3775 950);
WIRE 16 -1 (-3775 950)(-3575 950);
WIRE 16 -1 (-3775 850)(-3775 900);
WIRE 16 -1 (-3775 900)(-3575 900);
WIRE 16 -1 (-3775 800)(-3775 850);
WIRE 16 -1 (-3775 850)(-3575 850);
WIRE 16 -1 (-3775 750)(-3775 800);
WIRE 16 -1 (-3775 800)(-3575 800);
WIRE 16 -1 (-3775 700)(-3775 750);
WIRE 16 -1 (-3775 750)(-3575 750);
WIRE 16 -1 (-3775 650)(-3775 700);
WIRE 16 -1 (-3775 700)(-3575 700);
WIRE 16 -1 (-3775 600)(-3775 650);
WIRE 16 -1 (-3775 650)(-3575 650);
WIRE 16 -1 (-3775 600)(-3575 600);
WIRE 16 -1 (-3925 2100)(-3925 2000);
WIRE 16 -1 (-3925 2000)(-3775 2000);
WIRE 16 -1 (-3775 1950)(-3775 2000);
WIRE 16 -1 (-3775 2000)(-3575 2000);
WIRE 16 -1 (-3775 1950)(-3575 1950);
WIRE 16 -1 (-7825 1650)(-7825 1550);
WIRE 16 -1 (-5850 1550)(-7825 1550);
WIRE 16 -1 (-5850 1450)(-5850 1550);
WIRE 16 -1 (-5725 1550)(-5850 1550);
WIRE 16 -1 (-5850 1400)(-5850 1450);
WIRE 16 -1 (-5725 1450)(-5850 1450);
WIRE 16 -1 (-5725 1400)(-5850 1400);
WIRE 16 -1 (-3775 2400)(-3775 2300);
WIRE 16 -1 (-3775 2250)(-3775 2300);
WIRE 16 -1 (-3775 2300)(-3575 2300);
WIRE 16 -1 (-3775 2200)(-3775 2250);
WIRE 16 -1 (-3775 2250)(-3575 2250);
WIRE 16 -1 (-3775 2150)(-3775 2200);
WIRE 16 -1 (-3775 2200)(-3575 2200);
WIRE 16 -1 (-3775 2100)(-3775 2150);
WIRE 16 -1 (-3775 2150)(-3575 2150);
WIRE 16 -1 (-3775 2100)(-3575 2100);
WIRE 17 -1 (-1925 2925)(-1925 3025);
WIRE 17 -1 (-1925 3025)(-1925 3125);
WIRE 17 -1 (-1925 3125)(-1925 3225);
WIRE 17 -1 (-1925 3225)(-1925 3325);
WIRE 17 -1 (-1925 3325)(-1925 3425);
WIRE 17 -1 (-1925 3425)(-1925 3525);
WIRE 17 -1 (-1925 3525)(-1925 3625);
WIRE 17 -1 (-1925 3625)(-1925 3725);
WIRE 17 -1 (-1925 3725)(-1925 3825);
WIRE 17 -1 (-1925 3825)(-1925 3925);
WIRE 17 -1 (-1925 3925)(-1925 4025);
WIRE 17 -1 (-1925 4025)(-1925 4125);
WIRE 17 -1 (-1925 4125)(-1925 4225);
WIRE 17 -1 (-1925 4225)(-1925 4325);
WIRE 17 -1 (-1925 4325)(-1925 4425);
WIRE 17 -1 (-1925 4425)(-1925 4525);
WIRE 17 -1 (-1125 4650)(-1925 4650);
FORCEPROP 2 LAST SIG_NAME M_H_DQS_DP<17:0>
J 0
(-1700 4660);
DISPLAY 0.617021 (-1700 4660);
PAINT ORANGE (-1700 4660);
WIRE 17 -1 (-1925 4525)(-1925 4625);
WIRE 17 -1 (-1925 4625)(-1925 4650);
WIRE 17 -1 (-1725 2875)(-1725 2975);
WIRE 17 -1 (-1725 2975)(-1725 3075);
WIRE 17 -1 (-1725 3075)(-1725 3175);
WIRE 17 -1 (-1725 3175)(-1725 3275);
WIRE 17 -1 (-1725 3275)(-1725 3375);
WIRE 17 -1 (-1725 3375)(-1725 3475);
WIRE 17 -1 (-1725 3475)(-1725 3575);
WIRE 17 -1 (-1725 3575)(-1725 3675);
WIRE 17 -1 (-1725 3675)(-1725 3775);
WIRE 17 -1 (-1725 3775)(-1725 3875);
WIRE 17 -1 (-1725 3875)(-1725 3975);
WIRE 17 -1 (-1725 3975)(-1725 4075);
WIRE 17 -1 (-1725 4075)(-1725 4175);
WIRE 17 -1 (-1725 4175)(-1725 4275);
WIRE 17 -1 (-1725 4275)(-1725 4375);
WIRE 17 -1 (-1725 4375)(-1725 4475);
WIRE 17 -1 (-1125 4600)(-1725 4600);
FORCEPROP 2 LAST SIG_NAME M_H_DQS_DN<17:0>
J 0
(-1700 4610);
DISPLAY 0.617021 (-1700 4610);
PAINT ORANGE (-1700 4610);
WIRE 17 -1 (-1725 4475)(-1725 4575);
WIRE 17 -1 (-1725 4575)(-1725 4600);
WIRE 17 -1 (-4425 1225)(-4425 1275);
WIRE 17 -1 (-4425 1275)(-4425 1325);
WIRE 17 -1 (-4425 1325)(-4425 1375);
WIRE 17 -1 (-4425 1375)(-4425 1425);
WIRE 17 -1 (-4425 1425)(-4425 1475);
WIRE 17 -1 (-4425 1475)(-4425 1525);
WIRE 17 -1 (-4425 1525)(-4425 1575);
WIRE 17 -1 (-4425 1575)(-4425 1625);
WIRE 17 -1 (-4425 1625)(-4425 1675);
WIRE 17 -1 (-4425 1675)(-4425 1725);
WIRE 17 -1 (-4425 1725)(-4425 1775);
WIRE 17 -1 (-4425 1775)(-4425 1825);
WIRE 17 -1 (-4425 1825)(-4425 1875);
WIRE 17 -1 (-4425 1875)(-4425 1925);
WIRE 17 -1 (-4425 1925)(-4425 1975);
WIRE 17 -1 (-4425 1975)(-4425 2025);
WIRE 17 -1 (-4425 2025)(-4425 2075);
WIRE 17 -1 (-4425 2075)(-4425 2125);
WIRE 17 -1 (-4425 2125)(-4425 2175);
WIRE 17 -1 (-4425 2175)(-4425 2225);
WIRE 17 -1 (-4425 2225)(-4425 2275);
WIRE 17 -1 (-4425 2275)(-4425 2325);
WIRE 17 -1 (-4425 2325)(-4425 2375);
WIRE 17 -1 (-4425 2375)(-4425 2425);
WIRE 17 -1 (-4425 2425)(-4425 2475);
WIRE 17 -1 (-4425 2475)(-4425 2525);
WIRE 17 -1 (-4425 2525)(-4425 2575);
WIRE 17 -1 (-4425 2575)(-4425 2625);
WIRE 17 -1 (-4425 2625)(-4425 2675);
WIRE 17 -1 (-4425 2675)(-4425 2725);
WIRE 17 -1 (-4425 2725)(-4425 2775);
WIRE 17 -1 (-4425 2775)(-4425 2825);
WIRE 17 -1 (-4425 2825)(-4425 2875);
WIRE 17 -1 (-4425 2875)(-4425 2925);
WIRE 17 -1 (-4425 2925)(-4425 2975);
WIRE 17 -1 (-4425 2975)(-4425 3025);
WIRE 17 -1 (-4425 3025)(-4425 3075);
WIRE 17 -1 (-4425 3075)(-4425 3125);
WIRE 17 -1 (-4425 3125)(-4425 3175);
WIRE 17 -1 (-4425 3175)(-4425 3225);
WIRE 17 -1 (-4425 3225)(-4425 3275);
WIRE 17 -1 (-4425 3275)(-4425 3325);
WIRE 17 -1 (-4425 3325)(-4425 3375);
WIRE 17 -1 (-4425 3375)(-4425 3425);
WIRE 17 -1 (-4425 3425)(-4425 3475);
WIRE 17 -1 (-4425 3475)(-4425 3525);
WIRE 17 -1 (-4425 3525)(-4425 3575);
WIRE 17 -1 (-4425 3575)(-4425 3625);
WIRE 17 -1 (-4425 3625)(-4425 3675);
WIRE 17 -1 (-4425 3675)(-4425 3725);
WIRE 17 -1 (-4425 3725)(-4425 3775);
WIRE 17 -1 (-4425 3775)(-4425 3825);
WIRE 17 -1 (-4425 3825)(-4425 3875);
WIRE 17 -1 (-4425 3875)(-4425 3925);
WIRE 17 -1 (-4425 3925)(-4425 3975);
WIRE 17 -1 (-4425 3975)(-4425 4025);
WIRE 17 -1 (-4425 4025)(-4425 4075);
WIRE 17 -1 (-4425 4075)(-4425 4125);
WIRE 17 -1 (-3925 4400)(-4425 4400);
FORCEPROP 2 LAST SIG_NAME M_H_DQ<63:0>
J 0
(-4385 4410);
DISPLAY 0.617021 (-4385 4410);
PAINT ORANGE (-4385 4410);
WIRE 17 -1 (-4425 4125)(-4425 4175);
WIRE 17 -1 (-4425 4175)(-4425 4225);
WIRE 17 -1 (-4425 4375)(-4425 4400);
WIRE 17 -1 (-4425 4325)(-4425 4375);
WIRE 17 -1 (-4425 4225)(-4425 4275);
WIRE 17 -1 (-4425 4275)(-4425 4325);
WIRE 17 -1 (-6025 3525)(-6025 3575);
WIRE 17 -1 (-6025 3575)(-6025 3625);
WIRE 17 -1 (-6025 3625)(-6025 3675);
WIRE 17 -1 (-6025 3675)(-6025 3725);
WIRE 17 -1 (-6025 3725)(-6025 3775);
WIRE 17 -1 (-6025 3775)(-6025 3825);
WIRE 17 -1 (-6025 3825)(-6025 3875);
WIRE 17 -1 (-6025 3875)(-6025 3925);
WIRE 17 -1 (-6025 3925)(-6025 3975);
WIRE 17 -1 (-6025 3975)(-6025 4025);
WIRE 17 -1 (-6025 4025)(-6025 4075);
WIRE 17 -1 (-6025 4075)(-6025 4125);
WIRE 17 -1 (-6025 4125)(-6025 4175);
WIRE 17 -1 (-6025 4175)(-6025 4225);
WIRE 17 -1 (-6025 4225)(-6025 4275);
WIRE 17 -1 (-6575 4400)(-6025 4400);
FORCEPROP 2 LAST SIG_NAME M_H_MA<17:0>
J 0
(-6525 4410);
DISPLAY 0.617021 (-6525 4410);
PAINT ORANGE (-6525 4410);
WIRE 17 -1 (-6025 4375)(-6025 4400);
WIRE 17 -1 (-6025 4275)(-6025 4325);
WIRE 17 -1 (-6025 4325)(-6025 4375);
WIRE 17 -1 (-6225 3125)(-6225 3025);
WIRE 17 -1 (-6225 3150)(-6575 3150);
FORCEPROP 2 LAST SIG_NAME M_H_CLK_DN<3:0>
J 0
(-6525 3160);
DISPLAY 0.617021 (-6525 3160);
PAINT ORANGE (-6525 3160);
WIRE 17 -1 (-6225 3150)(-6225 3125);
WIRE 17 -1 (-6025 3075)(-6025 3175);
WIRE 17 -1 (-6025 3200)(-6575 3200);
FORCEPROP 2 LAST SIG_NAME M_H_CLK_DP<3:0>
J 0
(-6525 3210);
DISPLAY 0.617021 (-6525 3210);
PAINT ORANGE (-6525 3210);
WIRE 17 -1 (-6025 3200)(-6025 3175);
WIRE 17 -1 (-6025 3450)(-6575 3450);
FORCEPROP 2 LAST SIG_NAME M_H_BA<1:0>
J 0
(-6525 3460);
DISPLAY 0.617021 (-6525 3460);
PAINT ORANGE (-6525 3460);
WIRE 17 -1 (-6025 3450)(-6025 3425);
WIRE 17 -1 (-6025 3375)(-6025 3425);
WIRE 17 -1 (-6025 3275)(-6025 3325);
WIRE 17 -1 (-6025 3350)(-6575 3350);
FORCEPROP 2 LAST SIG_NAME M_H_BG<1:0>
J 0
(-6525 3360);
DISPLAY 0.617021 (-6525 3360);
PAINT ORANGE (-6525 3360);
WIRE 17 -1 (-6025 3350)(-6025 3325);
WIRE 17 -1 (-6025 2900)(-6575 2900);
FORCEPROP 2 LAST SIG_NAME M_H_CS_N<7:0>
J 0
(-6550 2910);
DISPLAY 0.617021 (-6550 2910);
PAINT ORANGE (-6550 2910);
WIRE 17 -1 (-6025 2900)(-6025 2875);
WIRE 17 -1 (-6025 2825)(-6025 2875);
WIRE 17 -1 (-6025 2775)(-6025 2825);
WIRE 17 -1 (-6025 2725)(-6025 2775);
WIRE 17 -1 (-6025 2650)(-6575 2650);
FORCEPROP 2 LAST SIG_NAME M_H_CKE<3:0>
J 0
(-6550 2660);
DISPLAY 0.617021 (-6550 2660);
PAINT ORANGE (-6550 2660);
WIRE 17 -1 (-6025 2650)(-6025 2625);
WIRE 17 -1 (-6025 2575)(-6025 2625);
WIRE 17 -1 (-6025 2425)(-6025 2475);
WIRE 17 -1 (-6025 2500)(-6575 2500);
FORCEPROP 2 LAST SIG_NAME M_H_ODT<3:0>
J 0
(-6550 2510);
DISPLAY 0.617021 (-6550 2510);
PAINT ORANGE (-6550 2510);
WIRE 17 -1 (-6025 2500)(-6025 2475);
WIRE 17 -1 (-6025 1975)(-6025 2025);
WIRE 17 -1 (-6025 2025)(-6025 2075);
WIRE 17 -1 (-6025 2075)(-6025 2125);
WIRE 17 -1 (-6025 2125)(-6025 2175);
WIRE 17 -1 (-6025 2175)(-6025 2225);
WIRE 17 -1 (-6025 2225)(-6025 2275);
WIRE 17 -1 (-6025 2275)(-6025 2325);
WIRE 17 -1 (-6025 2350)(-6575 2350);
FORCEPROP 2 LAST SIG_NAME M_H_ECC<7:0>
J 0
(-6550 2360);
DISPLAY 0.617021 (-6550 2360);
PAINT ORANGE (-6550 2360);
WIRE 17 -1 (-6025 2350)(-6025 2325);
WIRE 16 -1 (-2025 3600)(-2225 3600);
WIRE 16 -1 (-2025 3500)(-2225 3500);
WIRE 16 -1 (-4525 4050)(-4725 4050);
WIRE 16 -1 (-2025 3900)(-2225 3900);
WIRE 16 -1 (-1825 3850)(-2225 3850);
WIRE 16 -1 (-4525 4350)(-4725 4350);
WIRE 16 -1 (-4525 3500)(-4725 3500);
WIRE 16 -1 (-1825 3250)(-2225 3250);
WIRE 16 -1 (-2025 3200)(-2225 3200);
WIRE 16 -1 (-1825 3150)(-2225 3150);
WIRE 16 -1 (-4525 4150)(-4725 4150);
WIRE 16 -1 (-4525 3850)(-4725 3850);
WIRE 16 -1 (-4525 3800)(-4725 3800);
WIRE 16 -1 (-6175 2050)(-6900 2050);
FORCEPROP 2 LAST SIG_NAME FM_DIMM_EVENT_COD_N
J 0
(-6855 2060);
DISPLAY 0.617021 (-6855 2060);
PAINT ORANGE (-6855 2060);
WIRE 16 -1 (-6175 1750)(-6175 2050);
WIRE 16 -1 (-6175 1750)(-5725 1750);
WIRE 16 -1 (-7225 1200)(-7225 1100);
WIRE 16 -1 (-7275 1200)(-7225 1200);
WIRE 16 -1 (-5725 1200)(-7225 1200);
FORCEPROP 2 LAST SIG_NAME M_H_VREF
J 0
(-6525 1210);
DISPLAY 0.617021 (-6525 1210);
PAINT ORANGE (-6525 1210);
WIRE 16 -1 (-6575 1100)(-5725 1100);
FORCEPROP 2 LAST SIG_NAME TP_CH_H_DIMM0_RFU_2
J 0
(-6525 1110);
DISPLAY 0.617021 (-6525 1110);
PAINT ORANGE (-6525 1110);
FORCEPROP 2 LASTPROP $XRERR UNIQUE?
J 0
(-6815 1100);
DISPLAY 0.638298 (-6815 1100);
PAINT MONO (-6815 1100);
DISPLAY INVISIBLE (-6815 1100);
WIRE 16 -1 (-6575 1000)(-5725 1000);
FORCEPROP 2 LAST SIG_NAME TP_CH_H_DIMM0_RFU_0
J 0
(-6525 1010);
DISPLAY 0.617021 (-6525 1010);
PAINT ORANGE (-6525 1010);
FORCEPROP 2 LASTPROP $XRERR UNIQUE?
J 0
(-6815 1000);
DISPLAY 0.638298 (-6815 1000);
PAINT MONO (-6815 1000);
DISPLAY INVISIBLE (-6815 1000);
WIRE 16 -1 (-6575 1050)(-5725 1050);
FORCEPROP 2 LAST SIG_NAME TP_CH_H_DIMM0_RFU_1
J 0
(-6525 1060);
DISPLAY 0.617021 (-6525 1060);
PAINT ORANGE (-6525 1060);
FORCEPROP 2 LASTPROP $XRERR UNIQUE?
J 0
(-6815 1050);
DISPLAY 0.638298 (-6815 1050);
PAINT MONO (-6815 1050);
DISPLAY INVISIBLE (-6815 1050);
WIRE 16 -1 (-5725 1650)(-6575 1650);
FORCEPROP 2 LAST SIG_NAME M_H_ACT_N
J 0
(-6525 1660);
DISPLAY 0.617021 (-6525 1660);
PAINT ORANGE (-6525 1660);
WIRE 16 -1 (-6575 900)(-5725 900);
FORCEPROP 2 LAST SIG_NAME FM_ADR_COMPLETE_GHJ_N
J 0
(-6525 910);
DISPLAY 0.617021 (-6525 910);
PAINT ORANGE (-6525 910);
WIRE 16 -1 (-6575 1300)(-5725 1300);
FORCEPROP 2 LAST SIG_NAME SMB_DDR_GHJ_VPP_SCL
J 0
(-6535 1310);
DISPLAY 0.617021 (-6535 1310);
PAINT ORANGE (-6535 1310);
WIRE 16 -1 (-6575 1350)(-5725 1350);
WIRE 16 -1 (-5725 1700)(-6600 1700);
FORCEPROP 2 LAST SIG_NAME M_H_ALERT_N
J 0
(-6550 1710);
DISPLAY 0.617021 (-6550 1710);
PAINT ORANGE (-6550 1710);
WIRE 16 -1 (-5725 2000)(-5925 2000);
WIRE 16 -1 (-5725 1950)(-5925 1950);
WIRE 16 -1 (-4525 2000)(-4725 2000);
WIRE 16 -1 (-4525 1850)(-4725 1850);
WIRE 16 -1 (-4525 1750)(-4725 1750);
WIRE 16 -1 (-4525 1700)(-4725 1700);
WIRE 16 -1 (-4525 1600)(-4725 1600);
WIRE 16 -1 (-4525 1500)(-4725 1500);
WIRE 16 -1 (-4525 1250)(-4725 1250);
WIRE 16 -1 (-4525 1200)(-4725 1200);
WIRE 16 -1 (-4525 1950)(-4725 1950);
WIRE 16 -1 (-4525 1400)(-4725 1400);
WIRE 16 -1 (-4525 1300)(-4725 1300);
WIRE 16 -1 (-4525 1350)(-4725 1350);
WIRE 16 -1 (-4525 1550)(-4725 1550);
WIRE 16 -1 (-4525 1650)(-4725 1650);
WIRE 16 -1 (-4525 1900)(-4725 1900);
WIRE 16 -1 (-4525 1450)(-4725 1450);
WIRE 16 -1 (-4525 1800)(-4725 1800);
WIRE 16 -1 (-6075 2300)(-6575 2300);
FORCEPROP 2 LAST SIG_NAME M_H_PAR
J 0
(-6550 2310);
DISPLAY 0.617021 (-6550 2310);
PAINT ORANGE (-6550 2310);
WIRE 16 -1 (-5725 1850)(-6075 1850);
WIRE 16 -1 (-6075 1850)(-6075 2300);
WIRE 16 -1 (-6125 2250)(-6575 2250);
FORCEPROP 2 LAST SIG_NAME M_GHJ_RST_N
J 0
(-6550 2260);
DISPLAY 0.617021 (-6550 2260);
PAINT ORANGE (-6550 2260);
WIRE 16 -1 (-5725 1800)(-6125 1800);
WIRE 16 -1 (-6125 1800)(-6125 2250);
WIRE 16 -1 (-5725 2250)(-5925 2250);
WIRE 16 -1 (-5725 2200)(-5925 2200);
WIRE 16 -1 (-5725 2150)(-5925 2150);
WIRE 16 -1 (-5725 2100)(-5925 2100);
WIRE 16 -1 (-5725 2050)(-5925 2050);
WIRE 16 -1 (-5725 2300)(-5925 2300);
WIRE 16 -1 (-5725 2400)(-5925 2400);
WIRE 16 -1 (-5725 2450)(-5925 2450);
WIRE 16 -1 (-5725 2550)(-5925 2550);
WIRE 16 -1 (-5925 2950)(-6575 2950);
FORCEPROP 2 LAST SIG_NAME M_H_C<2>
J 0
(-6550 2960);
DISPLAY 0.617021 (-6550 2960);
PAINT ORANGE (-6550 2960);
WIRE 16 -1 (-5925 2950)(-5925 2900);
WIRE 16 -1 (-5925 2900)(-5725 2900);
WIRE 16 -1 (-5725 3050)(-5925 3050);
WIRE 16 -1 (-5725 2850)(-5925 2850);
WIRE 16 -1 (-5725 2800)(-5925 2800);
WIRE 16 -1 (-5725 2750)(-5925 2750);
WIRE 16 -1 (-5725 2600)(-5925 2600);
WIRE 16 -1 (-5725 2700)(-5925 2700);
WIRE 16 -1 (-5725 3000)(-6125 3000);
WIRE 16 -1 (-5725 3400)(-5925 3400);
WIRE 16 -1 (-5725 3500)(-5925 3500);
WIRE 16 -1 (-5725 3550)(-5925 3550);
WIRE 16 -1 (-5725 3250)(-5925 3250);
WIRE 16 -1 (-5725 3300)(-5925 3300);
WIRE 16 -1 (-5725 3350)(-5925 3350);
WIRE 16 -1 (-5725 3150)(-5925 3150);
WIRE 16 -1 (-5725 3100)(-6125 3100);
WIRE 16 -1 (-5725 3650)(-5925 3650);
WIRE 16 -1 (-5725 3700)(-5925 3700);
WIRE 16 -1 (-5725 3750)(-5925 3750);
WIRE 16 -1 (-5725 3800)(-5925 3800);
WIRE 16 -1 (-5725 3850)(-5925 3850);
WIRE 16 -1 (-5725 3900)(-5925 3900);
WIRE 16 -1 (-5725 3950)(-5925 3950);
WIRE 16 -1 (-5725 3600)(-5925 3600);
WIRE 16 -1 (-5725 4000)(-5925 4000);
WIRE 16 -1 (-5725 4050)(-5925 4050);
WIRE 16 -1 (-4525 2650)(-4725 2650);
WIRE 16 -1 (-4525 2600)(-4725 2600);
WIRE 16 -1 (-4525 3050)(-4725 3050);
WIRE 16 -1 (-4525 2900)(-4725 2900);
WIRE 16 -1 (-4525 2850)(-4725 2850);
WIRE 16 -1 (-4525 2800)(-4725 2800);
WIRE 16 -1 (-4525 2750)(-4725 2750);
WIRE 16 -1 (-4525 2700)(-4725 2700);
WIRE 16 -1 (-4525 2400)(-4725 2400);
WIRE 16 -1 (-4525 2300)(-4725 2300);
WIRE 16 -1 (-4525 2250)(-4725 2250);
WIRE 16 -1 (-4525 2200)(-4725 2200);
WIRE 16 -1 (-4525 2100)(-4725 2100);
WIRE 16 -1 (-4525 2950)(-4725 2950);
WIRE 16 -1 (-4525 3000)(-4725 3000);
WIRE 16 -1 (-4525 2550)(-4725 2550);
WIRE 16 -1 (-4525 2050)(-4725 2050);
WIRE 16 -1 (-4525 2350)(-4725 2350);
WIRE 16 -1 (-4525 2450)(-4725 2450);
WIRE 16 -1 (-4525 2500)(-4725 2500);
WIRE 16 -1 (-4525 2150)(-4725 2150);
WIRE 16 -1 (-4525 4000)(-4725 4000);
WIRE 16 -1 (-4525 3950)(-4725 3950);
WIRE 16 -1 (-4525 3450)(-4725 3450);
WIRE 16 -1 (-4525 3400)(-4725 3400);
WIRE 16 -1 (-4525 3350)(-4725 3350);
WIRE 16 -1 (-4525 3300)(-4725 3300);
WIRE 16 -1 (-4525 3250)(-4725 3250);
WIRE 16 -1 (-4525 3200)(-4725 3200);
WIRE 16 -1 (-4525 3150)(-4725 3150);
WIRE 16 -1 (-4525 3100)(-4725 3100);
WIRE 16 -1 (-4525 3900)(-4725 3900);
WIRE 16 -1 (-4525 3750)(-4725 3750);
WIRE 16 -1 (-4525 3650)(-4725 3650);
WIRE 16 -1 (-4525 3600)(-4725 3600);
WIRE 16 -1 (-4525 3550)(-4725 3550);
WIRE 16 -1 (-4525 3700)(-4725 3700);
WIRE 16 -1 (-5725 4100)(-5925 4100);
WIRE 16 -1 (-5725 4150)(-5925 4150);
WIRE 16 -1 (-5725 4350)(-5925 4350);
WIRE 16 -1 (-5725 4200)(-5925 4200);
WIRE 16 -1 (-5725 4250)(-5925 4250);
WIRE 16 -1 (-5725 4300)(-5925 4300);
WIRE 16 -1 (-4525 4250)(-4725 4250);
WIRE 16 -1 (-4525 4200)(-4725 4200);
WIRE 16 -1 (-4525 4100)(-4725 4100);
WIRE 16 -1 (-4525 4300)(-4725 4300);
WIRE 16 -1 (-1825 2850)(-2225 2850);
WIRE 16 -1 (-2025 2900)(-2225 2900);
WIRE 16 -1 (-1825 3950)(-2225 3950);
WIRE 16 -1 (-2025 4000)(-2225 4000);
WIRE 16 -1 (-1825 4050)(-2225 4050);
WIRE 16 -1 (-1825 2950)(-2225 2950);
WIRE 16 -1 (-2025 3000)(-2225 3000);
WIRE 16 -1 (-1825 3050)(-2225 3050);
WIRE 16 -1 (-2025 3100)(-2225 3100);
WIRE 16 -1 (-2025 3300)(-2225 3300);
WIRE 16 -1 (-1825 3350)(-2225 3350);
WIRE 16 -1 (-2025 3400)(-2225 3400);
WIRE 16 -1 (-1825 3450)(-2225 3450);
WIRE 16 -1 (-1825 3550)(-2225 3550);
WIRE 16 -1 (-1825 3650)(-2225 3650);
WIRE 16 -1 (-2025 3700)(-2225 3700);
WIRE 16 -1 (-1825 3750)(-2225 3750);
WIRE 16 -1 (-2025 3800)(-2225 3800);
WIRE 16 -1 (-2025 4100)(-2225 4100);
WIRE 16 -1 (-1825 4150)(-2225 4150);
WIRE 16 -1 (-2025 4200)(-2225 4200);
WIRE 16 -1 (-1825 4250)(-2225 4250);
WIRE 16 -1 (-2025 4300)(-2225 4300);
WIRE 16 -1 (-1825 4350)(-2225 4350);
WIRE 16 -1 (-2025 4400)(-2225 4400);
WIRE 16 -1 (-1825 4450)(-2225 4450);
WIRE 16 -1 (-2025 4500)(-2225 4500);
WIRE 16 -1 (-1825 4550)(-2225 4550);
WIRE 16 -1 (-2025 4600)(-2225 4600);
DOT 1 (-2375 2300);
DOT 1 (-1575 2300);
DOT 1 (-175 750);
DOT 1 (-1575 2100);
DOT 1 (-5850 1450);
DOT 1 (-5850 1550);
DOT 1 (-3775 950);
DOT 1 (-3775 700);
DOT 1 (-7225 1200);
DOT 1 (-3775 650);
DOT 1 (-3775 800);
DOT 1 (-3775 850);
DOT 1 (-3775 900);
DOT 1 (-3775 750);
DOT 1 (-3775 1050);
DOT 1 (-3775 1100);
DOT 1 (-3775 1200);
DOT 1 (-3775 1150);
DOT 1 (-3775 1000);
DOT 1 (-3775 1250);
DOT 1 (-3775 1300);
DOT 1 (-3775 1350);
DOT 1 (-3775 1400);
DOT 1 (-3775 1450);
DOT 1 (-3775 1500);
DOT 1 (-3775 1600);
DOT 1 (-3775 1650);
DOT 1 (-3775 1700);
DOT 1 (-3775 1750);
DOT 1 (-3775 1550);
DOT 1 (-3775 2000);
DOT 1 (-3775 1850);
DOT 1 (-3775 2200);
DOT 1 (-3775 2250);
DOT 1 (-3775 2150);
DOT 1 (-3775 2300);
DOT 1 (-1575 700);
DOT 1 (-1575 750);
DOT 1 (-1575 800);
DOT 1 (-1575 850);
DOT 1 (-1575 900);
DOT 1 (-1575 950);
DOT 1 (-1575 1000);
DOT 1 (-1575 1050);
DOT 1 (-1575 1100);
DOT 1 (-1575 1150);
DOT 1 (-1575 1200);
DOT 1 (-1575 1250);
DOT 1 (-1575 1300);
DOT 1 (-1575 1350);
DOT 1 (-1575 1400);
DOT 1 (-1575 1450);
DOT 1 (-1575 1500);
DOT 1 (-1575 1550);
DOT 1 (-1575 1600);
DOT 1 (-1575 1650);
DOT 1 (-1575 1700);
DOT 1 (-1575 1750);
DOT 1 (-1575 1850);
DOT 1 (-1575 1800);
DOT 1 (-1575 1900);
DOT 1 (-1575 2000);
DOT 1 (-1575 2050);
DOT 1 (-1575 2150);
DOT 1 (-1575 2200);
DOT 1 (-1575 2250);
DOT 1 (-1575 2350);
DOT 1 (-1575 2400);
DOT 1 (-1575 2450);
DOT 1 (-1575 2500);
DOT 1 (-1575 2550);
DOT 1 (-1575 2650);
DOT 1 (-1575 2600);
DOT 1 (-1575 2700);
DOT 1 (-1575 2750);
DOT 1 (-1575 2800);
DOT 1 (-1575 2850);
DOT 1 (-1575 2900);
DOT 1 (-1575 2950);
DOT 1 (-175 700);
DOT 1 (-175 800);
DOT 1 (-175 850);
DOT 1 (-175 900);
DOT 1 (-175 950);
DOT 1 (-175 1000);
DOT 1 (-175 1050);
DOT 1 (-175 1100);
DOT 1 (-175 1150);
DOT 1 (-175 1200);
DOT 1 (-175 1250);
DOT 1 (-175 1300);
DOT 1 (-175 1350);
DOT 1 (-175 1400);
DOT 1 (-175 1450);
DOT 1 (-175 1500);
DOT 1 (-175 1550);
DOT 1 (-175 1600);
DOT 1 (-175 1650);
DOT 1 (-175 1700);
DOT 1 (-175 1750);
DOT 1 (-175 1800);
DOT 1 (-175 1850);
DOT 1 (-175 1900);
DOT 1 (-175 1950);
DOT 1 (-175 2000);
DOT 1 (-175 2050);
DOT 1 (-175 2100);
DOT 1 (-175 2150);
DOT 1 (-175 2200);
DOT 1 (-175 2250);
DOT 1 (-175 2300);
DOT 1 (-175 2350);
DOT 1 (-175 2400);
DOT 1 (-175 2450);
DOT 1 (-175 2500);
DOT 1 (-175 2550);
DOT 1 (-175 2650);
DOT 1 (-175 2600);
DOT 1 (-175 2700);
DOT 1 (-175 2750);
DOT 1 (-175 2800);
DOT 1 (-175 2850);
DOT 1 (-175 2900);
DOT 1 (-175 2950);
DOT 1 (-1575 1950);
DOT 1 (-3775 1800);
FORCENOTE
PVDDQ (SINGLE SIDE) CAP: 10UF X1, 22UF X50
(-5475 4750) 0;
DISPLAY LEFT (-5475 4750);
DISPLAY 1.021277 (-5475 4750);
PAINT PURPLE (-5475 4750);
FORCENOTE
PVTT CAP: 100UF X2, 47UF X1
(-5475 4800) 0;
DISPLAY LEFT (-5475 4800);
DISPLAY 1.021277 (-5475 4800);
PAINT PURPLE (-5475 4800);
FORCENOTE
PVPP CAP: 10UF X12
(-5475 4850) 0;
DISPLAY LEFT (-5475 4850);
DISPLAY 1.021277 (-5475 4850);
PAINT PURPLE (-5475 4850);
FORCENOTE
PVDDQ (DOUBLE SIDE) CAP: 100UF X8, 47UF X41
(-5475 4700) 0;
DISPLAY LEFT (-5475 4700);
DISPLAY 1.021277 (-5475 4700);
PAINT PURPLE (-5475 4700);
FORCENOTE
CAP BETWEEN DIMM
(-5475 4925) 0;
DISPLAY LEFT (-5475 4925);
DISPLAY 1.276596 (-5475 4925);
PAINT PURPLE (-5475 4925);
FORCENOTE
SMBUS ADDR: 0XA6
(-7900 275) 0;
DISPLAY LEFT (-7900 275);
DISPLAY 1.957447 (-7900 275);
PAINT PURPLE (-7900 275);
FORCENOTE
PLACE CAP NEAR DIMM CONNECTOR
(-7913 502) 0;
DISPLAY LEFT (-7913 502);
DISPLAY 1.574468 (-7913 502);
PAINT PURPLE (-7913 502);
QUIT
